G04 ================== begin FILE IDENTIFICATION RECORD ==================*
G04 Layout Name:  15968-1a.brd*
G04 Film Name:    TSILK*
G04 File Format:  Gerber RS274X*
G04 File Origin:  Cadence Allegro 16.5-S058*
G04 Origin Date:  Fri Oct 14 10:23:31 2016*
G04 *
G04 Layer:  VIA CLASS/FILMMASKTOP*
G04 Layer:  REF DES/ASSEMBLY_TOP*
G04 Layer:  PACKAGE GEOMETRY/SILKSCREEN_TOP*
G04 Layer:  DRAWING FORMAT/LAYER_PCB_STORY*
G04 Layer:  DRAWING FORMAT/LAYER_SILK_T*
G04 Layer:  BOARD GEOMETRY/SILKSCREEN_TOP*
G04 *
G04 Offset:    (0.00 0.00)*
G04 Mirror:    No*
G04 Mode:      Positive*
G04 Rotation:  0*
G04 FullContactRelief:  No*
G04 UndefLineWidth:     6.00*
G04 ================== end FILE IDENTIFICATION RECORD ====================*
%FSLAX35Y35*MOIN*%
%IR0*IPPOS*OFA0.00000B0.00000*MIA0B0*SFA1.00000B1.00000*%
%ADD10C,.01*%
%ADD11C,.02*%
%ADD12C,.012*%
%ADD13C,.013*%
%ADD14C,.014*%
%ADD15C,.015*%
%ADD16C,.018*%
%ADD17C,.019*%
%ADD18C,.002*%
%ADD19C,.003*%
%ADD20C,.005*%
%ADD21C,.006*%
%ADD22C,.008*%
G75*
%LPD*%
G75*
G36*
G01X64897Y192044D02*
X90537D01*
Y177444D01*
X64897D01*
Y192044D01*
G37*
G36*
G01X89079Y135387D02*
Y130387D01*
X84079D01*
X89079Y135387D01*
G37*
G36*
G01X114575Y87864D02*
Y82864D01*
X109575D01*
X114575Y87864D01*
G37*
G36*
G01X278344Y197803D02*
Y172163D01*
X263744D01*
Y197803D01*
X278344D01*
G37*
G36*
G01X197390Y184498D02*
Y176498D01*
X206490D01*
Y184498D01*
X197390D01*
G37*
G36*
G01X359538Y31769D02*
Y2469D01*
X345538D01*
Y31769D01*
X359538D01*
G37*
G36*
G01X425587Y-16922D02*
X425648Y-17409D01*
X425708Y-17469D01*
X425769Y-18199D01*
X425830Y-18260D01*
X425891Y-19051D01*
X425952Y-19112D01*
X426013Y-19842D01*
X426073Y-19902D01*
X426134Y-20632D01*
X426195Y-20693D01*
X426256Y-21423D01*
X426317Y-21484D01*
X426377Y-22214D01*
X426438Y-22274D01*
X426499Y-23065D01*
X426560Y-23126D01*
X426621Y-23856D01*
X426682Y-23916D01*
X426742Y-24646D01*
X426803Y-24707D01*
X426864Y-25437D01*
X426925Y-25498D01*
X426986Y-26227D01*
X427047Y-26288D01*
X427107Y-27018D01*
X427168Y-27079D01*
X427229Y-27869D01*
X427290Y-27930D01*
X427351Y-28660D01*
X427412Y-28721D01*
X427472Y-29147D01*
X431912D01*
X432095Y-28904D01*
X432216Y-28599D01*
X432399Y-28356D01*
X432520Y-28052D01*
X432703Y-27809D01*
X432764Y-27627D01*
X432946Y-27383D01*
X433067Y-27079D01*
X433250Y-26836D01*
X433372Y-26532D01*
X433554Y-26288D01*
X433676Y-25984D01*
X433858Y-25741D01*
X433919Y-25558D01*
X434101Y-25315D01*
X434223Y-25011D01*
X434406Y-24768D01*
X434527Y-24464D01*
X434710Y-24221D01*
X434831Y-23916D01*
X435014Y-23673D01*
X435136Y-23369D01*
X435318Y-23126D01*
X435379Y-22943D01*
X435561Y-22700D01*
X435683Y-22396D01*
X435865Y-22153D01*
X435987Y-21849D01*
X436169Y-21605D01*
Y-21544D01*
X436291Y-21423D01*
X436352Y-21484D01*
X436413Y-22579D01*
X436473Y-22639D01*
X436534Y-23734D01*
X436595Y-23795D01*
X436656Y-24890D01*
X436717Y-24950D01*
X436778Y-26106D01*
X436838Y-26167D01*
X436899Y-27262D01*
X436960Y-27322D01*
X437021Y-28417D01*
X437082Y-28478D01*
X437142Y-29147D01*
X441582D01*
X441704Y-28843D01*
X441886Y-28599D01*
X441947Y-28417D01*
X442130Y-28174D01*
X442190Y-27991D01*
X442373Y-27748D01*
X442434Y-27566D01*
X442616Y-27322D01*
X442738Y-27018D01*
X442920Y-26775D01*
X442981Y-26592D01*
X443164Y-26349D01*
X443225Y-26167D01*
X443407Y-25923D01*
X443467Y-25741D01*
X443650Y-25498D01*
X443711Y-25315D01*
X443893Y-25072D01*
X443954Y-24890D01*
X444137Y-24646D01*
X444197Y-24464D01*
X444380Y-24221D01*
X444441Y-24038D01*
X444623Y-23795D01*
X444684Y-23612D01*
X444867Y-23369D01*
X444988Y-23065D01*
X445171Y-22822D01*
X445231Y-22639D01*
X445414Y-22396D01*
X445475Y-22214D01*
X445657Y-21970D01*
X445718Y-21788D01*
X445901Y-21544D01*
X445961Y-21362D01*
X446144Y-21119D01*
X446204Y-20936D01*
X446387Y-20693D01*
X446448Y-20510D01*
X446630Y-20267D01*
X446691Y-20085D01*
X446873Y-19842D01*
X446934Y-19659D01*
X447117Y-19416D01*
X447238Y-19112D01*
X447421Y-18868D01*
X447482Y-18686D01*
X447664Y-18443D01*
X447725Y-18260D01*
X447908Y-18017D01*
X447968Y-17834D01*
X448151Y-17591D01*
X448212Y-17409D01*
X448394Y-17166D01*
X448455Y-16983D01*
X448637Y-16740D01*
X448698Y-16557D01*
X448880Y-16314D01*
Y-16253D01*
X448941Y-16192D01*
X443832D01*
X443772Y-16436D01*
X443529Y-16861D01*
X443467Y-17105D01*
X443285Y-17409D01*
X443225Y-17652D01*
X443103Y-17834D01*
X443042Y-18078D01*
X442860Y-18382D01*
X442799Y-18625D01*
X442616Y-18929D01*
X442555Y-19173D01*
X442434Y-19355D01*
X442373Y-19598D01*
X442190Y-19902D01*
X442130Y-20145D01*
X441947Y-20450D01*
X441886Y-20693D01*
X441765Y-20875D01*
X441704Y-21119D01*
X441521Y-21423D01*
X441461Y-21666D01*
X441278Y-21970D01*
X441217Y-22214D01*
X441096Y-22396D01*
X441035Y-22639D01*
X440853Y-22943D01*
X440791Y-23186D01*
X440609Y-23491D01*
X440548Y-23734D01*
X440427Y-23916D01*
X440366Y-24160D01*
X440244Y-24281D01*
X440184Y-24221D01*
X440123Y-23004D01*
X440062Y-22943D01*
X440001Y-21666D01*
X439940Y-21605D01*
X439879Y-20328D01*
X439819Y-20267D01*
X439758Y-18929D01*
X439697Y-18868D01*
X439636Y-17591D01*
X439575Y-17530D01*
X439514Y-16253D01*
X439454Y-16192D01*
X434953D01*
X434771Y-16618D01*
X434588Y-16861D01*
X434406Y-17287D01*
X434223Y-17530D01*
X434041Y-17956D01*
X433858Y-18199D01*
X433676Y-18625D01*
X433493Y-18868D01*
X433372Y-19173D01*
X433189Y-19416D01*
X433007Y-19842D01*
X432824Y-20085D01*
X432642Y-20510D01*
X432459Y-20754D01*
X432338Y-21058D01*
X432155Y-21301D01*
X431973Y-21727D01*
X431790Y-21970D01*
X431608Y-22396D01*
X431425Y-22639D01*
X431243Y-23065D01*
X431060Y-23308D01*
X430939Y-23612D01*
X430756Y-23856D01*
X430574Y-24281D01*
X430453Y-24403D01*
X430391Y-24342D01*
X430331Y-22396D01*
X430270Y-22335D01*
X430209Y-20328D01*
X430148Y-20267D01*
X430088Y-18260D01*
X430027Y-18199D01*
X429966Y-16192D01*
X425465D01*
X425587Y-16922D01*
G37*
G36*
G01X403040Y16502D02*
Y24502D01*
X393940D01*
Y16502D01*
X403040D01*
G37*
G36*
G01X412707Y-26776D02*
Y-17732D01*
X417983D01*
Y-19239D01*
X414215D01*
Y-21500D01*
X416476D01*
Y-23008D01*
X414215D01*
Y-26776D01*
X412707D01*
G37*
G36*
G01X405170D02*
Y-17732D01*
X406678D01*
Y-21500D01*
X409692D01*
Y-17732D01*
X411200D01*
Y-26776D01*
X409692D01*
Y-23008D01*
X406678D01*
Y-26776D01*
X405170D01*
G37*
G36*
G01X362738Y68769D02*
Y39469D01*
X348738D01*
Y68769D01*
X362738D01*
G37*
G36*
G01X505199Y-15949D02*
X504469Y-16010D01*
X504408Y-16071D01*
X504043Y-16132D01*
X503983Y-16192D01*
X503679Y-16253D01*
X503618Y-16314D01*
X503375Y-16375D01*
X503314Y-16436D01*
X503071Y-16497D01*
X502827Y-16618D01*
X502584Y-16801D01*
X502523D01*
X502219Y-17044D01*
X502158D01*
X501672Y-17469D01*
X501611D01*
X500942Y-18139D01*
X500881Y-18078D01*
X500942Y-17591D01*
X501003Y-17530D01*
X501064Y-17044D01*
X501124Y-16983D01*
X501185Y-16497D01*
X501246Y-16436D01*
Y-16192D01*
X496624D01*
X496563Y-16618D01*
X496502Y-16679D01*
X496441Y-17226D01*
X496380Y-17287D01*
X496319Y-17774D01*
X496259Y-17834D01*
X496198Y-18321D01*
X496137Y-18382D01*
X496076Y-18929D01*
X496016Y-18990D01*
X495954Y-19477D01*
X495894Y-19538D01*
X495833Y-20024D01*
X495772Y-20085D01*
X495711Y-20571D01*
X495651Y-20632D01*
X495590Y-21180D01*
X495529Y-21240D01*
X495468Y-21727D01*
X495407Y-21788D01*
X495347Y-22274D01*
X495286Y-22335D01*
X495225Y-22882D01*
X495164Y-22943D01*
X495103Y-23430D01*
X495042Y-23491D01*
X494982Y-23977D01*
X494921Y-24038D01*
X494860Y-24586D01*
X494799Y-24646D01*
X494738Y-25133D01*
X494677Y-25193D01*
X494617Y-25680D01*
X494556Y-25741D01*
X494495Y-26227D01*
X494434Y-26288D01*
X494373Y-26836D01*
X494312Y-26897D01*
X494252Y-27383D01*
X494191Y-27444D01*
X494130Y-27930D01*
X494069Y-27991D01*
X494008Y-28539D01*
X493947Y-28599D01*
X493887Y-29086D01*
X493826Y-29147D01*
X498874D01*
X498935Y-28599D01*
X498995Y-28539D01*
X499056Y-28052D01*
X499117Y-27991D01*
X499178Y-27505D01*
X499239Y-27444D01*
X499300Y-26957D01*
X499360Y-26897D01*
X499421Y-26410D01*
X499482Y-26349D01*
X499543Y-25802D01*
X499604Y-25741D01*
X499665Y-25255D01*
X499725Y-25193D01*
X499786Y-24707D01*
X499847Y-24646D01*
X499908Y-24160D01*
X499969Y-24099D01*
X500030Y-23612D01*
X500090Y-23551D01*
X500151Y-23065D01*
X500212Y-23004D01*
X500273Y-22639D01*
X500334Y-22579D01*
X500394Y-22274D01*
X500455Y-22214D01*
X500516Y-21909D01*
X500942Y-21058D01*
X501185Y-20754D01*
Y-20693D01*
X501732Y-20085D01*
X502036Y-19842D01*
X502523Y-19598D01*
X503010Y-19538D01*
X503071Y-19477D01*
X503679Y-19538D01*
X504043Y-19842D01*
X504165Y-20024D01*
X504226Y-20510D01*
X504165Y-21301D01*
X504104Y-21362D01*
X504043Y-21909D01*
X503983Y-21970D01*
X503922Y-22517D01*
X503861Y-22579D01*
X503800Y-23126D01*
X503740Y-23186D01*
X503679Y-23673D01*
X503618Y-23734D01*
X503557Y-24281D01*
X503496Y-24342D01*
X503435Y-24829D01*
X503375Y-24890D01*
X503314Y-25376D01*
X503253Y-25437D01*
X503192Y-25984D01*
X503131Y-26045D01*
X503071Y-26532D01*
X503010Y-26592D01*
X502949Y-27140D01*
X502888Y-27201D01*
X502827Y-27687D01*
X502766Y-27748D01*
X502706Y-28234D01*
X502645Y-28295D01*
X502584Y-28843D01*
X502523Y-28904D01*
Y-29147D01*
X507449D01*
X507510Y-28843D01*
X507571Y-28782D01*
X507632Y-28234D01*
X507693Y-28174D01*
X507754Y-27687D01*
X507814Y-27627D01*
X507875Y-27079D01*
X507936Y-27018D01*
X507997Y-26532D01*
X508058Y-26471D01*
X508118Y-25984D01*
X508179Y-25923D01*
X508240Y-25376D01*
X508301Y-25315D01*
X508362Y-24829D01*
X508423Y-24768D01*
X508483Y-24221D01*
X508544Y-24160D01*
X508605Y-23673D01*
X508666Y-23612D01*
X508727Y-23126D01*
X508788Y-23065D01*
X508848Y-22517D01*
X508909Y-22457D01*
X508970Y-21970D01*
X509031Y-21909D01*
X509091Y-21362D01*
X509153Y-21301D01*
X509213Y-20693D01*
X509274Y-20632D01*
X509335Y-19963D01*
X509396Y-19902D01*
X509456Y-18929D01*
X509396Y-18199D01*
X509335Y-18139D01*
X509274Y-17834D01*
X509213Y-17774D01*
X509153Y-17530D01*
X508970Y-17287D01*
Y-17226D01*
X508544Y-16740D01*
X508118Y-16375D01*
X507754Y-16192D01*
X507510Y-16132D01*
X507449Y-16071D01*
X507024Y-16010D01*
X506963Y-15949D01*
X505990Y-15888D01*
X505260D01*
X505199Y-15949D01*
G37*
G36*
G01X490481Y-16436D02*
X490299Y-16679D01*
X490238Y-16861D01*
X490055Y-17105D01*
X489994Y-17287D01*
X489812Y-17530D01*
X489751Y-17713D01*
X489569Y-17956D01*
X489447Y-18260D01*
X489264Y-18503D01*
X489204Y-18686D01*
X489021Y-18929D01*
X488960Y-19112D01*
X488778Y-19355D01*
X488717Y-19538D01*
X488535Y-19781D01*
X488413Y-20085D01*
X488230Y-20328D01*
X488170Y-20510D01*
X487987Y-20754D01*
X487927Y-20936D01*
X487744Y-21180D01*
X487683Y-21362D01*
X487501Y-21605D01*
X487440Y-21788D01*
X487258Y-22031D01*
X487136Y-22335D01*
X486953Y-22579D01*
X486893Y-22761D01*
X486710Y-23004D01*
X486649Y-23186D01*
X486467Y-23430D01*
Y-23491D01*
X486345Y-23612D01*
X486284Y-23551D01*
X486223Y-22579D01*
X486163Y-22517D01*
X486102Y-21362D01*
X486041Y-21301D01*
X485980Y-20085D01*
X485919Y-20024D01*
X485859Y-18868D01*
X485798Y-18808D01*
X485737Y-17591D01*
X485676Y-17530D01*
X485616Y-16375D01*
X485554Y-16314D01*
Y-16192D01*
X480689D01*
X480750Y-16253D01*
X480811Y-16861D01*
X480871Y-16922D01*
X480932Y-17530D01*
X480993Y-17591D01*
X481054Y-18139D01*
X481115Y-18199D01*
X481176Y-18808D01*
X481236Y-18868D01*
X481297Y-19477D01*
X481358Y-19538D01*
X481419Y-20085D01*
X481480Y-20145D01*
X481540Y-20754D01*
X481601Y-20815D01*
X481662Y-21423D01*
X481723Y-21484D01*
X481784Y-22031D01*
X481845Y-22092D01*
X481905Y-22700D01*
X481966Y-22761D01*
X482027Y-23369D01*
X482088Y-23430D01*
X482149Y-23977D01*
X482210Y-24038D01*
X482270Y-24646D01*
X482331Y-24707D01*
X482392Y-25315D01*
X482453Y-25376D01*
X482514Y-25923D01*
X482575Y-25984D01*
X482635Y-26592D01*
X482696Y-26653D01*
X482757Y-27262D01*
X482817Y-27322D01*
X482879Y-27869D01*
X482939Y-27930D01*
X483000Y-28539D01*
X483061Y-28599D01*
X483122Y-29208D01*
X483182Y-29269D01*
X483061Y-29512D01*
X482879Y-29755D01*
X482757Y-30059D01*
X482575Y-30303D01*
X482514Y-30485D01*
X482331Y-30728D01*
X482270Y-30910D01*
X482088Y-31154D01*
X482027Y-31336D01*
X481845Y-31580D01*
X481723Y-31884D01*
X481540Y-32127D01*
X481480Y-32310D01*
X481297Y-32553D01*
X481236Y-32735D01*
X481054Y-32979D01*
X480993Y-33161D01*
X480811Y-33404D01*
X480689Y-33708D01*
X480506Y-33952D01*
X480446Y-34134D01*
X480263Y-34377D01*
X480203Y-34560D01*
X480020Y-34803D01*
X479959Y-34986D01*
X479777Y-35229D01*
X479655Y-35533D01*
X479534Y-35655D01*
X484642D01*
X484703Y-35472D01*
X484886Y-35229D01*
X484946Y-35046D01*
X485129Y-34803D01*
X485190Y-34621D01*
X485372Y-34377D01*
X485494Y-34073D01*
X485676Y-33830D01*
X485737Y-33647D01*
X485919Y-33404D01*
X485980Y-33222D01*
X486163Y-32979D01*
X486223Y-32796D01*
X486406Y-32553D01*
X486528Y-32249D01*
X486710Y-32005D01*
X486771Y-31823D01*
X486953Y-31580D01*
X487014Y-31397D01*
X487197Y-31154D01*
X487258Y-30971D01*
X487440Y-30728D01*
X487501Y-30546D01*
X487683Y-30303D01*
X487805Y-29998D01*
X487987Y-29755D01*
X488048Y-29573D01*
X488230Y-29329D01*
X488291Y-29147D01*
X488474Y-28904D01*
X488535Y-28721D01*
X488717Y-28478D01*
X488839Y-28174D01*
X489021Y-27930D01*
X489082Y-27748D01*
X489264Y-27505D01*
X489325Y-27322D01*
X489508Y-27079D01*
X489569Y-26897D01*
X489751Y-26653D01*
X489873Y-26349D01*
X490055Y-26106D01*
X490116Y-25923D01*
X490299Y-25680D01*
X490359Y-25498D01*
X490542Y-25255D01*
X490603Y-25072D01*
X490785Y-24829D01*
X490846Y-24646D01*
X491028Y-24403D01*
X491150Y-24099D01*
X491332Y-23856D01*
X491393Y-23673D01*
X491576Y-23430D01*
X491636Y-23247D01*
X491819Y-23004D01*
X491880Y-22822D01*
X492062Y-22579D01*
X492184Y-22274D01*
X492366Y-22031D01*
X492427Y-21849D01*
X492610Y-21605D01*
X492670Y-21423D01*
X492853Y-21180D01*
X492914Y-20997D01*
X493096Y-20754D01*
X493218Y-20450D01*
X493400Y-20206D01*
X493461Y-20024D01*
X493643Y-19781D01*
X493704Y-19598D01*
X493887Y-19355D01*
X493947Y-19173D01*
X494130Y-18929D01*
X494252Y-18625D01*
X494434Y-18382D01*
X494495Y-18199D01*
X494677Y-17956D01*
X494738Y-17774D01*
X494921Y-17530D01*
X494982Y-17348D01*
X495164Y-17105D01*
X495225Y-16922D01*
X495407Y-16679D01*
X495529Y-16375D01*
X495651Y-16253D01*
Y-16132D01*
X490603D01*
X490481Y-16436D01*
G37*
G36*
G01X456301Y-16740D02*
X456361Y-16801D01*
X456422Y-17591D01*
X456483Y-17652D01*
X456544Y-18382D01*
X456604Y-18443D01*
X456666Y-19173D01*
X456726Y-19233D01*
X456787Y-19963D01*
X456848Y-20024D01*
X456909Y-20754D01*
X456969Y-20815D01*
X457030Y-21544D01*
X457091Y-21605D01*
X457152Y-22396D01*
X457213Y-22457D01*
X457274Y-23186D01*
X457334Y-23247D01*
X457395Y-23977D01*
X457456Y-24038D01*
X457517Y-24768D01*
X457578Y-24829D01*
X457638Y-25558D01*
X457699Y-25619D01*
X457760Y-26349D01*
X457821Y-26410D01*
X457882Y-27201D01*
X457943Y-27262D01*
X458003Y-27991D01*
X458064Y-28052D01*
X458125Y-28782D01*
X458186Y-28843D01*
Y-29147D01*
X462686D01*
X462808Y-28904D01*
X462991Y-28660D01*
X463112Y-28356D01*
X463295Y-28113D01*
X463416Y-27809D01*
X463599Y-27566D01*
X463721Y-27262D01*
X463903Y-27018D01*
X464025Y-26714D01*
X464207Y-26471D01*
X464329Y-26167D01*
X464511Y-25923D01*
X464572Y-25741D01*
X464754Y-25498D01*
X464876Y-25193D01*
X465058Y-24950D01*
X465180Y-24646D01*
X465363Y-24403D01*
X465484Y-24099D01*
X465667Y-23856D01*
X465788Y-23551D01*
X465971Y-23308D01*
X466092Y-23004D01*
X466275Y-22761D01*
X466336Y-22579D01*
X466518Y-22335D01*
X466640Y-22031D01*
X466822Y-21788D01*
X467005Y-21423D01*
X467066Y-21484D01*
X467126Y-21970D01*
X467187Y-22700D01*
X467248Y-23065D01*
X467309Y-23916D01*
X467369Y-23977D01*
X467430Y-25072D01*
X467491Y-25133D01*
X467552Y-26227D01*
X467613Y-26288D01*
X467674Y-27444D01*
X467734Y-27505D01*
X467795Y-28599D01*
X467856Y-28660D01*
Y-29147D01*
X472296D01*
X472417Y-28904D01*
X472600Y-28660D01*
X472661Y-28478D01*
X472843Y-28234D01*
X472904Y-28052D01*
X473087Y-27809D01*
X473147Y-27627D01*
X473330Y-27383D01*
X473391Y-27201D01*
X473573Y-26957D01*
X473634Y-26775D01*
X473816Y-26532D01*
X473877Y-26349D01*
X474060Y-26106D01*
X474121Y-25923D01*
X474303Y-25680D01*
X474364Y-25498D01*
X474546Y-25255D01*
X474668Y-24950D01*
X474851Y-24707D01*
X474911Y-24525D01*
X475093Y-24281D01*
X475154Y-24099D01*
X475337Y-23856D01*
X475398Y-23673D01*
X475580Y-23430D01*
X475641Y-23247D01*
X475823Y-23004D01*
X475884Y-22822D01*
X476067Y-22579D01*
X476128Y-22396D01*
X476310Y-22153D01*
X476371Y-21970D01*
X476553Y-21727D01*
X476614Y-21544D01*
X476797Y-21301D01*
X476857Y-21119D01*
X477040Y-20875D01*
X477162Y-20571D01*
X477344Y-20328D01*
X477405Y-20145D01*
X477587Y-19902D01*
X477648Y-19720D01*
X477830Y-19477D01*
X477891Y-19294D01*
X478074Y-19051D01*
X478134Y-18868D01*
X478317Y-18625D01*
X478378Y-18443D01*
X478560Y-18199D01*
X478621Y-18017D01*
X478804Y-17774D01*
X478864Y-17591D01*
X479047Y-17348D01*
X479108Y-17166D01*
X479290Y-16922D01*
X479412Y-16618D01*
X479594Y-16375D01*
X479655Y-16253D01*
Y-16192D01*
X474607D01*
X474364Y-16679D01*
X474303Y-16922D01*
X474121Y-17226D01*
X474060Y-17469D01*
X473938Y-17652D01*
X473877Y-17895D01*
X473695Y-18199D01*
X473634Y-18443D01*
X473451Y-18747D01*
X473391Y-18990D01*
X473269Y-19173D01*
X473208Y-19416D01*
X473026Y-19720D01*
X472965Y-19963D01*
X472782Y-20267D01*
X472722Y-20510D01*
X472600Y-20693D01*
X472539Y-20936D01*
X472357Y-21240D01*
X472296Y-21484D01*
X472114Y-21788D01*
X472053Y-22031D01*
X471931Y-22214D01*
X471870Y-22457D01*
X471688Y-22761D01*
X471627Y-23004D01*
X471445Y-23308D01*
X471384Y-23551D01*
X471262Y-23734D01*
X471201Y-23977D01*
X471019Y-24281D01*
X470958Y-24221D01*
X470897Y-23247D01*
X470836Y-22882D01*
X470775Y-21909D01*
X470715Y-21544D01*
X470654Y-20571D01*
X470593Y-20206D01*
X470532Y-19233D01*
X470471Y-18868D01*
X470410Y-17895D01*
X470350Y-17530D01*
X470289Y-16557D01*
X470228Y-16192D01*
X465727D01*
Y-16253D01*
X465545Y-16497D01*
X465363Y-16922D01*
X465180Y-17166D01*
X464998Y-17591D01*
X464815Y-17834D01*
X464633Y-18260D01*
X464450Y-18503D01*
X464329Y-18808D01*
X464146Y-19051D01*
X463964Y-19477D01*
X463781Y-19720D01*
X463599Y-20145D01*
X463416Y-20389D01*
X463234Y-20815D01*
X463051Y-21058D01*
X462930Y-21362D01*
X462747Y-21605D01*
X462565Y-22031D01*
X462382Y-22274D01*
X462200Y-22700D01*
X462017Y-22943D01*
X461835Y-23369D01*
X461653Y-23612D01*
X461531Y-23916D01*
X461349Y-24160D01*
X461227Y-24403D01*
X461166Y-24342D01*
X461105Y-23004D01*
X461044Y-22274D01*
X460984Y-20936D01*
X460923Y-20206D01*
X460862Y-18868D01*
X460801Y-18017D01*
X460740Y-16801D01*
X460680Y-16192D01*
X456240D01*
X456301Y-16740D01*
G37*
G36*
G01X453381Y-9745D02*
X452895Y-9806D01*
X452712Y-9928D01*
X452469Y-9989D01*
X452226Y-10110D01*
X451921Y-10354D01*
X451861D01*
X451192Y-11084D01*
Y-11144D01*
X451009Y-11388D01*
X450888Y-11631D01*
X450827Y-11935D01*
X450766Y-11996D01*
X450705Y-12604D01*
X450766Y-13395D01*
X450827Y-13456D01*
X450888Y-13699D01*
X451070Y-13942D01*
Y-14003D01*
X451617Y-14490D01*
X451678D01*
X451800Y-14611D01*
X452043Y-14672D01*
X452104Y-14733D01*
X452591Y-14793D01*
X452651Y-14855D01*
X453625Y-14793D01*
X453685Y-14733D01*
X453990Y-14672D01*
X454050Y-14611D01*
X454293Y-14550D01*
X454537Y-14429D01*
X454902Y-14125D01*
X454962D01*
X455632Y-13395D01*
X455692Y-13212D01*
X455875Y-12969D01*
X455936Y-12726D01*
X455997Y-12665D01*
X456057Y-12178D01*
X456118Y-12117D01*
X456057Y-11205D01*
X455997Y-11144D01*
X455936Y-10901D01*
X455814Y-10658D01*
X455388Y-10171D01*
X455145Y-9989D01*
X454780Y-9806D01*
X454354Y-9745D01*
X454293Y-9685D01*
X453442D01*
X453381Y-9745D01*
G37*
G36*
G01X449854Y-16557D02*
X449793Y-16618D01*
X449732Y-17105D01*
X449671Y-17166D01*
X449610Y-17652D01*
X449550Y-17713D01*
X449489Y-18260D01*
X449428Y-18321D01*
X449367Y-18808D01*
X449306Y-18868D01*
X449245Y-19355D01*
X449185Y-19416D01*
X449124Y-19963D01*
X449063Y-20024D01*
X449002Y-20510D01*
X448941Y-20571D01*
X448880Y-21058D01*
X448820Y-21119D01*
X448759Y-21666D01*
X448698Y-21727D01*
X448637Y-22214D01*
X448577Y-22274D01*
X448516Y-22761D01*
X448455Y-22822D01*
X448394Y-23369D01*
X448333Y-23430D01*
X448272Y-23916D01*
X448212Y-23977D01*
X448151Y-24464D01*
X448090Y-24525D01*
X448029Y-25072D01*
X447968Y-25133D01*
X447908Y-25619D01*
X447847Y-25680D01*
X447786Y-26167D01*
X447725Y-26227D01*
X447664Y-26775D01*
X447603Y-26836D01*
X447543Y-27322D01*
X447482Y-27383D01*
X447421Y-27869D01*
X447360Y-27930D01*
X447299Y-28478D01*
X447238Y-28539D01*
X447178Y-29025D01*
X447117Y-29086D01*
Y-29147D01*
X452469D01*
X452530Y-28782D01*
X452591Y-28721D01*
X452651Y-28234D01*
X452712Y-28174D01*
X452773Y-27627D01*
X452834Y-27566D01*
X452895Y-27079D01*
X452955Y-27018D01*
X453016Y-26532D01*
X453077Y-26471D01*
X453138Y-25923D01*
X453199Y-25863D01*
X453260Y-25376D01*
X453320Y-25315D01*
X453381Y-24829D01*
X453442Y-24768D01*
X453503Y-24221D01*
X453564Y-24160D01*
X453625Y-23673D01*
X453685Y-23612D01*
X453746Y-23126D01*
X453807Y-23065D01*
X453868Y-22517D01*
X453929Y-22457D01*
X453990Y-21970D01*
X454050Y-21909D01*
X454111Y-21423D01*
X454172Y-21362D01*
X454233Y-20875D01*
X454293Y-20815D01*
X454354Y-20267D01*
X454415Y-20206D01*
X454476Y-19720D01*
X454537Y-19659D01*
X454597Y-19173D01*
X454658Y-19112D01*
X454719Y-18564D01*
X454780Y-18503D01*
X454841Y-18017D01*
X454902Y-17956D01*
X454962Y-17469D01*
X455023Y-17409D01*
X455084Y-16861D01*
X455145Y-16801D01*
X455206Y-16314D01*
X455267Y-16253D01*
Y-16192D01*
X449914D01*
X449854Y-16557D01*
G37*
G36*
G01X498711Y9100D02*
G02I-11811J0D01*
G37*
G36*
G01X437019Y71860D02*
X442019D01*
Y66860D01*
X437019Y71860D01*
G37*
G36*
G01X474119Y73792D02*
Y70392D01*
X472419Y72092D01*
X474119Y73792D01*
G37*
G36*
G01X489800Y38900D02*
X495400D01*
Y40700D01*
X489800D01*
Y38900D01*
G37*
G36*
G01X492600Y34300D02*
X491705Y34390D01*
X490840Y34650D01*
X490045Y35075D01*
X489345Y35645D01*
X488775Y36345D01*
X488350Y37140D01*
X488090Y38005D01*
X488000Y38900D01*
X488090Y39795D01*
X488350Y40660D01*
X488775Y41455D01*
X489345Y42155D01*
X490045Y42725D01*
X490840Y43150D01*
X491705Y43410D01*
X492600Y43500D01*
X493495Y43410D01*
X494360Y43150D01*
X495155Y42725D01*
X495855Y42155D01*
X496425Y41455D01*
X496850Y40660D01*
X497110Y39795D01*
X497200Y38900D01*
X495400D01*
X495345Y39445D01*
X495185Y39970D01*
X494930Y40455D01*
X494580Y40880D01*
X494155Y41230D01*
X493670Y41485D01*
X493145Y41645D01*
X492600Y41700D01*
X492055Y41645D01*
X491530Y41485D01*
X491045Y41230D01*
X490620Y40880D01*
X490270Y40455D01*
X490015Y39970D01*
X489855Y39445D01*
X489800Y38900D01*
X489855Y38355D01*
X490015Y37830D01*
X490270Y37345D01*
X490620Y36920D01*
X491045Y36570D01*
X491530Y36315D01*
X492055Y36155D01*
X492600Y36100D01*
X493145Y36155D01*
X493670Y36315D01*
X494155Y36570D01*
X494580Y36920D01*
X494930Y37345D01*
X495100Y37670D01*
X496425Y36345D01*
X495855Y35645D01*
X495155Y35075D01*
X494360Y34650D01*
X493495Y34390D01*
X492600Y34300D01*
G37*
G36*
G01X500200Y34100D02*
Y40900D01*
X499600Y40300D01*
X498300Y41600D01*
X500400Y43700D01*
X502000D01*
Y34100D01*
X500200D01*
G37*
G36*
G01X527945Y-13699D02*
X528067Y-13942D01*
X527520D01*
X527459Y-13881D01*
X527277Y-13456D01*
X527094Y-13212D01*
Y-13091D01*
X526912Y-13030D01*
X526486Y-12969D01*
Y-13942D01*
X526060D01*
Y-12146D01*
X526486D01*
Y-12604D01*
X526790D01*
X527398Y-12543D01*
X527459Y-12361D01*
X527398Y-11996D01*
X527216D01*
X527155Y-11935D01*
X526486D01*
Y-12145D01*
X526060D01*
Y-11570D01*
X527216D01*
X527580Y-11631D01*
X527824Y-11814D01*
X527885Y-12056D01*
X527945Y-12117D01*
X527885Y-12482D01*
X527641Y-12786D01*
X527398Y-12847D01*
X527337Y-12908D01*
X527459Y-13030D01*
X527520D01*
X527580Y-13091D01*
X527702Y-13273D01*
X527763Y-13456D01*
X527945Y-13699D01*
G37*
G36*
G01X528432Y-14429D02*
X528128Y-14672D01*
X527885Y-14733D01*
X527702Y-14855D01*
X526668Y-14915D01*
X526608Y-14855D01*
X526243Y-14793D01*
X525878Y-14611D01*
X525634Y-14429D01*
X525209Y-13942D01*
X524966Y-13456D01*
X524904Y-12543D01*
X524905Y-12537D01*
X525290D01*
X525269Y-12726D01*
X525330Y-13334D01*
X525452Y-13577D01*
X525695Y-13881D01*
Y-13942D01*
X526121Y-14307D01*
X526364Y-14429D01*
X526790Y-14490D01*
X526851Y-14550D01*
X527580Y-14490D01*
X527641Y-14429D01*
X527885Y-14368D01*
X528250Y-14064D01*
X528675Y-13577D01*
X528736Y-13334D01*
X528797Y-13273D01*
X528858Y-12847D01*
X528797Y-12239D01*
X528736Y-12178D01*
X528675Y-11935D01*
X528371Y-11570D01*
Y-11449D01*
X528250D01*
X527885Y-11144D01*
X527763D01*
X527702Y-11084D01*
X527337Y-11023D01*
X527277Y-10962D01*
X526547Y-11023D01*
X526486Y-11084D01*
X526243Y-11144D01*
X525999Y-11327D01*
X525938D01*
X525513Y-11814D01*
X525330Y-12178D01*
X525290Y-12536D01*
X524905D01*
X524966Y-12056D01*
X525209Y-11570D01*
X525391Y-11327D01*
X525878Y-10901D01*
X526243Y-10719D01*
X526608Y-10658D01*
X526668Y-10597D01*
X527459D01*
X527520Y-10658D01*
X527885Y-10719D01*
X528128Y-10840D01*
X528432Y-11084D01*
X528493D01*
X528919Y-11570D01*
X529040Y-11814D01*
X529101Y-12056D01*
X529162Y-12117D01*
X529223Y-13212D01*
X529162Y-13273D01*
X529101Y-13577D01*
X528919Y-13942D01*
X528493Y-14429D01*
X528432D01*
G37*
G36*
G01X520647Y-15949D02*
X519917Y-16010D01*
X519856Y-16071D01*
X519431Y-16132D01*
X519370Y-16192D01*
X519066Y-16253D01*
X518884Y-16375D01*
X518640Y-16436D01*
X518032Y-16740D01*
X517728Y-16983D01*
X517667D01*
X517302Y-17287D01*
X517241D01*
X516329Y-18199D01*
X516268Y-18139D01*
X516329Y-17713D01*
X516390Y-17652D01*
X516451Y-17166D01*
X516512Y-17105D01*
X516572Y-16618D01*
X516633Y-16557D01*
X516694Y-16253D01*
Y-16192D01*
X512072D01*
X512011Y-16253D01*
X511950Y-16740D01*
X511889Y-16801D01*
X511829Y-17348D01*
X511767Y-17409D01*
X511707Y-17895D01*
X511646Y-17956D01*
X511585Y-18443D01*
X511524Y-18503D01*
X511464Y-19051D01*
X511403Y-19112D01*
X511342Y-19598D01*
X511281Y-19659D01*
X511220Y-20145D01*
X511159Y-20206D01*
X511099Y-20693D01*
X511038Y-20754D01*
X510977Y-21301D01*
X510916Y-21362D01*
X510855Y-21849D01*
X510795Y-21909D01*
X510734Y-22396D01*
X510673Y-22457D01*
X510612Y-23004D01*
X510551Y-23065D01*
X510490Y-23551D01*
X510430Y-23612D01*
X510369Y-24099D01*
X510308Y-24160D01*
X510247Y-24707D01*
X510186Y-24768D01*
X510125Y-25255D01*
X510065Y-25315D01*
X510004Y-25802D01*
X509943Y-25863D01*
X509882Y-26349D01*
X509821Y-26410D01*
X509760Y-26957D01*
X509700Y-27018D01*
X509639Y-27505D01*
X509578Y-27566D01*
X509517Y-28052D01*
X509456Y-28113D01*
X509396Y-28660D01*
X509335Y-28721D01*
X509274Y-29147D01*
X514261D01*
X514322Y-28782D01*
X514383Y-28721D01*
X514443Y-28174D01*
X514504Y-28113D01*
X514565Y-27627D01*
X514626Y-27566D01*
X514687Y-27079D01*
X514748Y-27018D01*
X514808Y-26532D01*
X514869Y-26471D01*
X514930Y-25984D01*
X514991Y-25923D01*
X515052Y-25376D01*
X515113Y-25315D01*
X515173Y-24829D01*
X515234Y-24768D01*
X515295Y-24281D01*
X515356Y-24221D01*
X515417Y-23734D01*
X515478Y-23673D01*
X515538Y-23186D01*
X515599Y-23126D01*
X515660Y-22700D01*
X515721Y-22639D01*
X515782Y-22335D01*
X515843Y-22274D01*
X515903Y-22031D01*
X515964Y-21970D01*
X516025Y-21727D01*
X516086Y-21666D01*
X516147Y-21423D01*
X516329Y-21180D01*
X516390Y-20997D01*
X516633Y-20693D01*
Y-20632D01*
X517059Y-20145D01*
X517120D01*
X517545Y-19781D01*
X517910Y-19598D01*
X518397Y-19538D01*
X518458Y-19477D01*
X519066Y-19538D01*
X519309Y-19720D01*
X519431D01*
Y-19842D01*
X519553Y-19963D01*
X519613Y-20328D01*
X519674Y-20389D01*
X519613Y-21119D01*
X519553Y-21180D01*
X519491Y-21788D01*
X519431Y-21849D01*
X519370Y-22396D01*
X519309Y-22457D01*
X519248Y-22943D01*
X519188Y-23004D01*
X519127Y-23551D01*
X519066Y-23612D01*
X519005Y-24099D01*
X518944Y-24160D01*
X518884Y-24646D01*
X518823Y-24707D01*
X518762Y-25255D01*
X518701Y-25315D01*
X518640Y-25802D01*
X518579Y-25863D01*
X518519Y-26410D01*
X518458Y-26471D01*
X518397Y-26957D01*
X518336Y-27018D01*
X518275Y-27505D01*
X518214Y-27566D01*
X518154Y-28113D01*
X518093Y-28174D01*
X518032Y-28660D01*
X517971Y-28721D01*
X517910Y-29147D01*
X522897D01*
X522958Y-28660D01*
X523019Y-28599D01*
X523080Y-28113D01*
X523141Y-28052D01*
X523202Y-27505D01*
X523262Y-27444D01*
X523323Y-26957D01*
X523384Y-26897D01*
X523445Y-26349D01*
X523506Y-26288D01*
X523567Y-25802D01*
X523627Y-25741D01*
X523688Y-25255D01*
X523749Y-25193D01*
X523810Y-24646D01*
X523871Y-24586D01*
X523931Y-24099D01*
X523992Y-24038D01*
X524053Y-23491D01*
X524114Y-23430D01*
X524175Y-22943D01*
X524236Y-22882D01*
X524296Y-22335D01*
X524357Y-22274D01*
X524418Y-21788D01*
X524479Y-21727D01*
X524540Y-21180D01*
X524601Y-21119D01*
X524661Y-20510D01*
X524722Y-20450D01*
X524783Y-19720D01*
X524844Y-19659D01*
X524783Y-18078D01*
X524722Y-18017D01*
X524661Y-17774D01*
X524601Y-17713D01*
Y-17591D01*
X524418Y-17348D01*
Y-17287D01*
X523992Y-16801D01*
X523506Y-16375D01*
X523019Y-16132D01*
X522715Y-16071D01*
X522654Y-16010D01*
X522046Y-15949D01*
X521985Y-15888D01*
X520708D01*
X520647Y-15949D01*
G37*
G36*
G01X508200Y8700D02*
Y3700D01*
X528200D01*
Y8700D01*
X508200D01*
G37*
G36*
G01X517020Y171802D02*
X512020D01*
Y176802D01*
X517020Y171802D01*
G37*
%LPC*%
G75*
G36*
G01X486900Y-1530D02*
X488975Y-1325D01*
X490970Y-720D01*
X492805Y260D01*
X493874Y1140D01*
X491434Y3580D01*
X491004D01*
X490906Y3588D01*
X490205Y3800D01*
X489880Y3975D01*
Y3580D01*
X488280D01*
Y6735D01*
X485563Y9452D01*
X485155Y9120D01*
X484519Y8779D01*
X483863Y8580D01*
X481305D01*
Y3580D01*
X479735D01*
Y15280D01*
X478940Y16074D01*
X478060Y15005D01*
X477080Y13170D01*
X476475Y11175D01*
X476270Y9100D01*
X476475Y7025D01*
X477080Y5030D01*
X478060Y3195D01*
X479385Y1585D01*
X480995Y260D01*
X482830Y-720D01*
X484825Y-1325D01*
X486900Y-1530D01*
G37*
G36*
G01X494859Y2125D02*
X495740Y3195D01*
X496720Y5030D01*
X497325Y7025D01*
X497530Y9100D01*
X497325Y11175D01*
X496720Y13170D01*
X495740Y15005D01*
X494415Y16615D01*
X492805Y17940D01*
X490970Y18920D01*
X488975Y19525D01*
X486900Y19730D01*
X484825Y19525D01*
X482830Y18920D01*
X480995Y17940D01*
X479924Y17058D01*
X481166Y15815D01*
X483555D01*
X483829Y15780D01*
X484520Y15570D01*
X485155Y15230D01*
X485715Y14775D01*
X486170Y14215D01*
X486510Y13580D01*
X486720Y12890D01*
X486790Y12175D01*
X486720Y11460D01*
X486510Y10770D01*
X486406Y10577D01*
X488280Y8703D01*
Y15620D01*
X489880D01*
Y11565D01*
X490205Y11740D01*
X490900Y11950D01*
X491625Y12020D01*
X492350Y11950D01*
X493045Y11740D01*
X493685Y11395D01*
X494245Y10935D01*
X494705Y10375D01*
X495050Y9735D01*
X495259Y9042D01*
X495330Y8315D01*
Y7225D01*
X495260Y6500D01*
X495050Y5805D01*
X494705Y5165D01*
X494245Y4605D01*
X493685Y4145D01*
X493135Y3849D01*
X494859Y2125D01*
G37*
G36*
G01X491935Y5049D02*
X492055Y5060D01*
X492471Y5190D01*
X492853Y5392D01*
X493189Y5669D01*
X493462Y6003D01*
X493663Y6384D01*
X493791Y6798D01*
X493830Y7225D01*
Y8315D01*
X493792Y8745D01*
X493660Y9160D01*
X493460Y9540D01*
X493185Y9875D01*
X492850Y10151D01*
X492468Y10351D01*
X492053Y10480D01*
X491626Y10520D01*
X491196Y10480D01*
X490780Y10350D01*
X490400Y10150D01*
X490065Y9875D01*
X489880Y9650D01*
Y7103D01*
X491935Y5049D01*
G37*
G36*
G01X481305Y10155D02*
X483915D01*
X483945Y10165D01*
X484325Y10365D01*
X484507Y10508D01*
X481305Y13710D01*
Y10155D01*
G37*
G36*
G01X485246Y11736D02*
X485250Y11750D01*
X485290Y12175D01*
X485250Y12600D01*
X485125Y13005D01*
X484925Y13385D01*
X484655Y13715D01*
X484325Y13985D01*
X483945Y14185D01*
X483860Y14215D01*
X482766D01*
X485246Y11736D01*
G37*
%LPD*%
G75*
G54D10*
G01X-21654Y344057D02*
G03Y354530I0J5236D01*
G01Y375552D02*
G03Y386025I0J5236D01*
G01Y407047D02*
G03Y417520I0J5236D01*
G01Y438543D02*
G03Y449015I0J5236D01*
G01Y470038D02*
G03Y480510I0J5236D01*
G01Y501533D02*
G03Y512005I0J5236D01*
G54D20*
G01X517489Y99288D02*
X520123Y99305D01*
X520949Y97209D01*
X517562D01*
X516780Y99276D01*
X517620Y99291D01*
G01X525243Y94048D02*
X522644Y101279D01*
G03X522456Y101602I-971J-349D01*
G01X527405Y94598D02*
X527429Y93881D01*
X524962Y93899D01*
G01X522377Y101604D02*
X514317Y101603D01*
G03X513219Y100218I0J-1128D01*
G01X514830Y95610D01*
G03X515833Y94881I1028J359D01*
G01X517576D01*
X516668Y90692D01*
X520021D01*
X520833Y94907D01*
X521692D01*
X523220Y90705D01*
X530477Y90708D01*
G03X531391Y91709I0J918D01*
G01Y92390D01*
X528045Y101597D01*
X524706D01*
X527740Y93648D01*
G01X539122Y94335D02*
G03X538836Y94848I-603J0D01*
G03X538024Y94944I-509J-824D01*
G02X537678Y94932I-194J588D01*
G03X537295Y94263I-98J-388D01*
G02X537284Y93786I-233J-233D01*
G01X537857Y93165D01*
X538967Y92532D01*
Y91410D01*
X538812Y90956D01*
X537988Y90920D01*
X537463Y91016D01*
X537176Y91314D01*
X537152Y91529D01*
G01X539342Y94086D02*
X538691D01*
Y94229D01*
G03X538381Y94713I-533J0D01*
G03X537587Y94134I-235J-511D01*
G03X538052Y93453I890J108D01*
G03X539145Y92878I29873J55458D01*
G01X538693Y92011D02*
Y91420D01*
G02X538609Y91217I-287J0D01*
G01X538526Y91134D01*
G02X538439Y91098I-87J87D01*
G01X537995D01*
G02X537687Y91225I-1J435D01*
G01X537559Y91354D01*
G02X537499Y91499I145J145D01*
G01Y91898D01*
X536807D01*
Y91438D01*
G03X537642Y90603I835J0D01*
G01X538619D01*
G03X539395Y91379I0J776D01*
G01Y92424D01*
G03X538858Y92961I-537J0D01*
G01X537628D01*
G01X539414Y94088D02*
Y94305D01*
G03X539128Y94995I-975J0D01*
G01X539111Y95012D01*
G03X538662Y95198I-449J-449D01*
G01X537564D01*
G03X537399Y95129I1J-234D01*
G01X537366Y95097D01*
G03X536901Y93974I1124J-1123D01*
G01Y93915D01*
G03X537188Y93222I980J0D01*
G01X537566Y92844D01*
G03X539409Y92214I1564J1564D01*
G01X533947Y95066D02*
Y91280D01*
X534161Y91066D01*
X535331D01*
X535546Y91281D01*
Y94719D01*
G01X533493Y95205D02*
Y91458D01*
G03X533767Y90797I934J0D01*
G03X534286Y90582I519J519D01*
G01X535320D01*
G03X535514Y90663I-1J275D01*
G01X535924Y91072D01*
G03X536092Y91478I-407J406D01*
G01Y95191D01*
X535292D01*
G01X512326Y94007D02*
Y94616D01*
X512051Y94891D01*
X510726D01*
X510475Y94640D01*
Y91249D01*
X510904Y90820D01*
X511956D01*
X512385Y91249D01*
Y91918D01*
G01X512004Y93829D02*
Y94056D01*
G03X511783Y94590I-756J0D01*
G03X511503Y94706I-280J-280D01*
G01X511287D01*
G03X510792Y94211I0J-495D01*
G01Y91494D01*
G03X511192Y91094I400J0D01*
G01X511448D01*
G03X511998Y91644I0J550D01*
G01Y92199D01*
X512786D01*
X512798Y92187D01*
Y91649D01*
G02X512236Y90624I-1216J0D01*
G01X512105Y90586D01*
X512100Y90581D01*
X510923D01*
G02X510001Y91503I0J922D01*
G01Y94377D01*
G02X510825Y95201I824J0D01*
G01X512043D01*
G02X512700Y94544I0J-657D01*
G01Y93780D01*
X512033D01*
X512005Y93808D01*
G54D11*
G01X-84798Y-164972D02*
Y-244972D01*
G01D02*
X1172402D01*
G01X-88798Y-148972D02*
G02I-12000J0D01*
G01X-93948D02*
G02I-6850J0D01*
G01X-100798Y-164972D02*
Y-132972D01*
G01X-84798Y-148972D02*
X-116798D01*
G01X-84798Y-164972D02*
X1172402D01*
G01X-84798Y-200472D02*
X1172402D01*
G01X66900Y84500D02*
Y79500D01*
G01X63717Y170444D02*
Y179244D01*
G01X106800Y194300D02*
Y199300D01*
G01X194940Y176198D02*
Y168498D01*
G01X256744Y198983D02*
X265544D01*
G01X384902Y-164972D02*
Y-244972D01*
G01X405490Y24802D02*
Y32502D01*
G01X522402Y-164972D02*
Y-244972D01*
G01X522460Y99578D02*
X523176Y93796D01*
X524084Y93987D01*
X523176Y96950D01*
X523678Y92195D01*
X523774Y91693D01*
X524682Y92983D01*
X524921Y91669D01*
X530368Y91837D01*
X530201Y92768D01*
X525876Y92912D01*
X529867Y93796D01*
X527262Y100701D01*
X525805Y100845D01*
X528098Y95086D01*
G01X514169Y100677D02*
X521720Y100749D01*
X522819Y94919D01*
X521242Y99722D01*
X520215Y100558D01*
X514217Y100032D01*
X515723Y95970D01*
X515794Y98694D01*
X516941Y95779D01*
X517825Y96257D01*
X521003Y96305D01*
X521290Y95803D01*
X518542Y95158D01*
X517777Y91502D01*
X519115Y91526D01*
X519785Y94345D01*
G01X521930Y228002D02*
X526930D01*
G01X529860D02*
X534860D01*
G01X537790D02*
X542790D01*
G01X545720D02*
X550720D01*
G01X637402Y-164972D02*
Y-244972D01*
G01X804902Y-164972D02*
Y-244972D01*
G01X974902Y-164972D02*
Y-244972D01*
G01X1172402Y-164972D02*
Y-244972D01*
G01X1200402Y-148972D02*
G02I-12000J0D01*
G01X1195252D02*
G02I-6850J0D01*
G01X1188402Y-164972D02*
Y-132972D01*
G01X1204402Y-148972D02*
X1172402D01*
G54D21*
G01X-65001Y-234972D02*
Y-217472D01*
X-60635D01*
X-58888Y-218347D01*
X-57578Y-219514D01*
X-56486Y-221263D01*
X-55613Y-223306D01*
X-55395Y-226222D01*
X-55613Y-229139D01*
X-56486Y-231181D01*
X-57578Y-232931D01*
X-58888Y-234097D01*
X-60635Y-234972D01*
X-65001D01*
G01X-48157Y-217472D02*
X-42698Y-234972D01*
X-37239Y-217472D01*
G01X-25198D02*
Y-234972D01*
G01X-30220Y-217472D02*
X-20176D01*
G01X5435Y-234972D02*
Y-217472D01*
X10894D01*
X12640Y-218347D01*
X13732Y-219514D01*
X14169Y-221847D01*
X13732Y-224181D01*
X12422Y-225639D01*
X10894Y-226514D01*
X5435D01*
G01X10894D02*
X14169Y-234972D01*
G01X27302Y-223306D02*
Y-234972D01*
G01Y-218639D02*
X26865Y-218347D01*
Y-217764D01*
X27302Y-217472D01*
X27739Y-217764D01*
Y-218347D01*
X27302Y-218639D01*
G01X41527Y-232931D02*
X42619Y-234097D01*
X44147Y-234972D01*
X45457D01*
X46767Y-234389D01*
X47640Y-233514D01*
X48077Y-232348D01*
X47859Y-230597D01*
X46985Y-229722D01*
X43055Y-227972D01*
X42182Y-225930D01*
X42619Y-224472D01*
X43492Y-223597D01*
X44802Y-223306D01*
X46112Y-223597D01*
X47422Y-224472D01*
G01X59027Y-227097D02*
X66014D01*
X65359Y-225055D01*
X64267Y-223889D01*
X62739Y-223306D01*
X61210Y-223597D01*
X59900Y-224472D01*
X59027Y-226514D01*
X58590Y-228264D01*
Y-230014D01*
X59027Y-231764D01*
X60119Y-233514D01*
X61429Y-234680D01*
X62957Y-234972D01*
X64485Y-234389D01*
X66014Y-232639D01*
G01X76745Y-234972D02*
Y-223306D01*
G01Y-225639D02*
X77837Y-224472D01*
X78929Y-223597D01*
X80457Y-223306D01*
X81548Y-223597D01*
X82859Y-224472D01*
G01X119605Y-218931D02*
X118295Y-218055D01*
X116767Y-217472D01*
X115020D01*
X113055Y-218347D01*
X111527Y-219805D01*
X110435Y-221556D01*
X109562Y-224472D01*
X109343Y-227097D01*
X109780Y-229722D01*
X110435Y-231472D01*
X111745Y-233222D01*
X113274Y-234389D01*
X114802Y-234972D01*
X116330D01*
X117859Y-234389D01*
X119169Y-233514D01*
X120261Y-232348D01*
G01X136232Y-234972D02*
Y-223306D01*
G01Y-225347D02*
X135359Y-224181D01*
X134048Y-223597D01*
X132520Y-223306D01*
X130992Y-223889D01*
X129682Y-225055D01*
X128808Y-226805D01*
X128372Y-229139D01*
X128808Y-231472D01*
X129682Y-233222D01*
X130992Y-234389D01*
X132520Y-234972D01*
X134048Y-234680D01*
X135359Y-233806D01*
X136232Y-232639D01*
G01X146745Y-234972D02*
Y-223306D01*
G01Y-225639D02*
X147837Y-224472D01*
X148929Y-223597D01*
X150457Y-223306D01*
X151548Y-223597D01*
X152859Y-224472D01*
G01X171232Y-217472D02*
Y-234972D01*
G01Y-232348D02*
X170359Y-233806D01*
X169048Y-234680D01*
X167520Y-234972D01*
X165774Y-234389D01*
X164464Y-232931D01*
X163590Y-231181D01*
X163372Y-229139D01*
X163590Y-227097D01*
X164464Y-225347D01*
X165774Y-223889D01*
X167520Y-223306D01*
X169048Y-223597D01*
X170140Y-224181D01*
X171232Y-225347D01*
G01X178252Y-240805D02*
X191352D01*
G01X197717Y-232639D02*
X199464Y-234097D01*
X201429Y-234972D01*
X203175D01*
X204922Y-234097D01*
X206232Y-232639D01*
X206887Y-230597D01*
X206450Y-228556D01*
X205359Y-226805D01*
X203394Y-225639D01*
X200774Y-225055D01*
X199245Y-223889D01*
X198590Y-221847D01*
X199027Y-219805D01*
X200119Y-218347D01*
X201647Y-217472D01*
X203175D01*
X204704Y-218055D01*
X206014Y-219514D01*
G01X215217Y-232639D02*
X216964Y-234097D01*
X218929Y-234972D01*
X220675D01*
X222422Y-234097D01*
X223732Y-232639D01*
X224387Y-230597D01*
X223950Y-228556D01*
X222859Y-226805D01*
X220894Y-225639D01*
X218274Y-225055D01*
X216745Y-223889D01*
X216090Y-221847D01*
X216527Y-219805D01*
X217619Y-218347D01*
X219147Y-217472D01*
X220675D01*
X222204Y-218055D01*
X223514Y-219514D01*
G01X250654Y-220389D02*
X251964Y-218639D01*
X253492Y-217764D01*
X255239Y-217472D01*
X257422Y-218055D01*
X258950Y-219514D01*
X259387Y-221263D01*
X259169Y-223014D01*
X258295Y-224472D01*
X253929Y-227389D01*
X251964Y-229430D01*
X250654Y-232348D01*
X250217Y-234972D01*
X259387D01*
G01X286527Y-232931D02*
X287619Y-234097D01*
X289147Y-234972D01*
X290457D01*
X291767Y-234389D01*
X292640Y-233514D01*
X293077Y-232348D01*
X292859Y-230597D01*
X291985Y-229722D01*
X288055Y-227972D01*
X287182Y-225930D01*
X287619Y-224472D01*
X288492Y-223597D01*
X289802Y-223306D01*
X291112Y-223597D01*
X292422Y-224472D01*
G01X307302Y-234972D02*
Y-217472D01*
G01X324802Y-234972D02*
X323492Y-234680D01*
X322182Y-233514D01*
X321308Y-231472D01*
X320872Y-229139D01*
X321308Y-226805D01*
X322182Y-224764D01*
X323492Y-223597D01*
X324802Y-223306D01*
X326112Y-223597D01*
X327422Y-224764D01*
X328295Y-226805D01*
X328514Y-229139D01*
X328295Y-231472D01*
X327422Y-233514D01*
X326112Y-234680D01*
X324802Y-234972D01*
G01X342302Y-217472D02*
Y-234972D01*
G01X339245Y-223306D02*
X345359D01*
G01X356527Y-232931D02*
X357619Y-234097D01*
X359147Y-234972D01*
X360457D01*
X361767Y-234389D01*
X362640Y-233514D01*
X363077Y-232348D01*
X362859Y-230597D01*
X361985Y-229722D01*
X358055Y-227972D01*
X357182Y-225930D01*
X357619Y-224472D01*
X358492Y-223597D01*
X359802Y-223306D01*
X361112Y-223597D01*
X362422Y-224472D01*
G01X109125Y-189972D02*
Y-172472D01*
X114802Y-187055D01*
X120479Y-172472D01*
Y-189972D01*
G01X132302D02*
X130992Y-189680D01*
X129682Y-188514D01*
X128808Y-186472D01*
X128372Y-184139D01*
X128808Y-181805D01*
X129682Y-179764D01*
X130992Y-178597D01*
X132302Y-178306D01*
X133612Y-178597D01*
X134922Y-179764D01*
X135795Y-181805D01*
X136014Y-184139D01*
X135795Y-186472D01*
X134922Y-188514D01*
X133612Y-189680D01*
X132302Y-189972D01*
G01X153732Y-172472D02*
Y-189972D01*
G01Y-187348D02*
X152859Y-188806D01*
X151548Y-189680D01*
X150020Y-189972D01*
X148274Y-189389D01*
X146964Y-187931D01*
X146090Y-186181D01*
X145872Y-184139D01*
X146090Y-182097D01*
X146964Y-180347D01*
X148274Y-178889D01*
X150020Y-178306D01*
X151548Y-178597D01*
X152640Y-179181D01*
X153732Y-180347D01*
G01X164027Y-182097D02*
X171014D01*
X170359Y-180055D01*
X169267Y-178889D01*
X167739Y-178306D01*
X166210Y-178597D01*
X164900Y-179472D01*
X164027Y-181514D01*
X163590Y-183264D01*
Y-185014D01*
X164027Y-186764D01*
X165119Y-188514D01*
X166429Y-189680D01*
X167957Y-189972D01*
X169485Y-189389D01*
X171014Y-187639D01*
G01X184802Y-189972D02*
Y-172472D01*
G01X418602Y-234972D02*
Y-217472D01*
X415982Y-220972D01*
G01Y-234972D02*
X421222D01*
G01X431299Y-232348D02*
X432608Y-233806D01*
X434137Y-234680D01*
X436102Y-234972D01*
X438067Y-234389D01*
X439595Y-233222D01*
X440687Y-231181D01*
X440905Y-228847D01*
X440469Y-226514D01*
X439377Y-225055D01*
X437848Y-223889D01*
X436320Y-223597D01*
X434792Y-223889D01*
X432827Y-225055D01*
X433482Y-217472D01*
X439377D01*
G01X449890Y-232931D02*
X451419Y-234389D01*
X453165Y-234972D01*
X454912Y-234389D01*
X456440Y-232639D01*
X457532Y-230014D01*
X457969Y-227389D01*
Y-224181D01*
X457532Y-221556D01*
X456440Y-219222D01*
X455130Y-218055D01*
X453602Y-217472D01*
X451855Y-218055D01*
X450545Y-219222D01*
X449672Y-220972D01*
X449235Y-223306D01*
X449672Y-225347D01*
X450764Y-227389D01*
X452074Y-228556D01*
X453602Y-228847D01*
X455348Y-228264D01*
X456659Y-226805D01*
X457969Y-224181D01*
G01X466954Y-227681D02*
X468482Y-225639D01*
X469792Y-224472D01*
X471539Y-223889D01*
X473067Y-224472D01*
X474159Y-225639D01*
X475032Y-227389D01*
X475250Y-229430D01*
X475032Y-231181D01*
X474159Y-232931D01*
X472848Y-234389D01*
X471320Y-234972D01*
X469574Y-234389D01*
X468045Y-232639D01*
X467172Y-230014D01*
X466954Y-227097D01*
X467390Y-223306D01*
X468045Y-221263D01*
X469137Y-219222D01*
X470665Y-217764D01*
X472194Y-217472D01*
X473722Y-218055D01*
X474814Y-219514D01*
G01X488602Y-234972D02*
X490130Y-234680D01*
X491877Y-233806D01*
X492969Y-232348D01*
X493405Y-230305D01*
X492969Y-228264D01*
X491659Y-226514D01*
X489694Y-225639D01*
X487510D01*
X486200Y-225055D01*
X485108Y-223597D01*
X484672Y-221556D01*
X485327Y-219514D01*
X486855Y-218055D01*
X488602Y-217472D01*
X490348Y-218055D01*
X491877Y-219514D01*
X492532Y-221556D01*
X492095Y-223597D01*
X491004Y-225055D01*
X489694Y-225639D01*
X487510D01*
X485545Y-226514D01*
X484235Y-228264D01*
X483799Y-230305D01*
X484235Y-232348D01*
X485327Y-233806D01*
X487074Y-234680D01*
X488602Y-234972D01*
G01X405485Y-189972D02*
Y-172472D01*
X410725D01*
X412472Y-173347D01*
X413782Y-175389D01*
X414219Y-177722D01*
X413782Y-180055D01*
X412690Y-181805D01*
X410725Y-182681D01*
X405485D01*
G01X432155Y-173931D02*
X430845Y-173055D01*
X429317Y-172472D01*
X427570D01*
X425605Y-173347D01*
X424077Y-174805D01*
X422985Y-176556D01*
X422112Y-179472D01*
X421893Y-182097D01*
X422330Y-184722D01*
X422985Y-186472D01*
X424295Y-188222D01*
X425824Y-189389D01*
X427352Y-189972D01*
X428880D01*
X430409Y-189389D01*
X431719Y-188514D01*
X432811Y-187348D01*
G01X446598Y-180639D02*
X447472Y-179764D01*
X448127Y-178306D01*
X448564Y-176263D01*
X448127Y-174514D01*
X447254Y-173347D01*
X445725Y-172472D01*
X439830D01*
Y-189972D01*
X447035D01*
X448564Y-188806D01*
X449437Y-187055D01*
X449874Y-185014D01*
X449437Y-182972D01*
X448127Y-181222D01*
X446598Y-180639D01*
X439830D01*
G01X455802Y-195805D02*
X468902D01*
G01X474830Y-189972D02*
Y-172472D01*
X484874Y-189972D01*
Y-172472D01*
G01X497352Y-189972D02*
X495605Y-189680D01*
X494077Y-188514D01*
X492767Y-186764D01*
X491893Y-184722D01*
X491457Y-182389D01*
Y-180055D01*
X491893Y-177722D01*
X492767Y-175680D01*
X494077Y-173931D01*
X495605Y-172764D01*
X497352Y-172472D01*
X499098Y-172764D01*
X500627Y-173931D01*
X501937Y-175680D01*
X502811Y-177722D01*
X503247Y-180055D01*
Y-182389D01*
X502811Y-184722D01*
X501937Y-186764D01*
X500627Y-188514D01*
X499098Y-189680D01*
X497352Y-189972D01*
G01X571152Y-234972D02*
Y-217472D01*
X568532Y-220972D01*
G01Y-234972D02*
X573772D01*
G01X583193D02*
X588652Y-217472D01*
X594111Y-234972D01*
G01X592145Y-228847D02*
X585158D01*
G01X548193Y-172472D02*
X553652Y-189972D01*
X559111Y-172472D01*
G01X575519Y-189972D02*
X566785D01*
Y-172472D01*
X575519D01*
G01X572025Y-180930D02*
X566785D01*
G01X584285Y-189972D02*
Y-172472D01*
X589744D01*
X591490Y-173347D01*
X592582Y-174514D01*
X593019Y-176847D01*
X592582Y-179181D01*
X591272Y-180639D01*
X589744Y-181514D01*
X584285D01*
G01X589744D02*
X593019Y-189972D01*
G01X606152Y-190555D02*
X605715Y-190264D01*
Y-189680D01*
X606152Y-189389D01*
X606589Y-189680D01*
Y-190264D01*
X606152Y-190555D01*
G01X686102Y-217472D02*
Y-234972D01*
G01X681080Y-217472D02*
X691124D01*
G01X699017Y-232639D02*
X700764Y-234097D01*
X702729Y-234972D01*
X704475D01*
X706222Y-234097D01*
X707532Y-232639D01*
X708187Y-230597D01*
X707750Y-228556D01*
X706659Y-226805D01*
X704694Y-225639D01*
X702074Y-225055D01*
X700545Y-223889D01*
X699890Y-221847D01*
X700327Y-219805D01*
X701419Y-218347D01*
X702947Y-217472D01*
X704475D01*
X706004Y-218055D01*
X707314Y-219514D01*
G01X718482Y-217472D02*
X723722D01*
G01X721102D02*
Y-234972D01*
G01X718482D02*
X723722D01*
G01X734235Y-217472D02*
Y-234972D01*
X742969D01*
G01X751299D02*
Y-217472D01*
G01X759595D02*
X751299Y-228264D01*
G01X760905Y-234972D02*
X755010Y-223306D01*
G01X681735Y-172472D02*
Y-189972D01*
X690469D01*
G01X707532D02*
Y-178306D01*
G01Y-180347D02*
X706659Y-179181D01*
X705348Y-178597D01*
X703820Y-178306D01*
X702292Y-178889D01*
X700982Y-180055D01*
X700108Y-181805D01*
X699672Y-184139D01*
X700108Y-186472D01*
X700982Y-188222D01*
X702292Y-189389D01*
X703820Y-189972D01*
X705348Y-189680D01*
X706659Y-188806D01*
X707532Y-187639D01*
G01X716517Y-195222D02*
X717827Y-195805D01*
X719574Y-195222D01*
X720665Y-194056D01*
X721539Y-192597D01*
X722848Y-187931D01*
X725687Y-178306D01*
G01X718700D02*
X722848Y-187931D01*
G01X735327Y-182097D02*
X742314D01*
X741659Y-180055D01*
X740567Y-178889D01*
X739039Y-178306D01*
X737510Y-178597D01*
X736200Y-179472D01*
X735327Y-181514D01*
X734890Y-183264D01*
Y-185014D01*
X735327Y-186764D01*
X736419Y-188514D01*
X737729Y-189680D01*
X739257Y-189972D01*
X740785Y-189389D01*
X742314Y-187639D01*
G01X753045Y-189972D02*
Y-178306D01*
G01Y-180639D02*
X754137Y-179472D01*
X755229Y-178597D01*
X756757Y-178306D01*
X757848Y-178597D01*
X759159Y-179472D01*
G01X824705Y-218931D02*
X823395Y-218055D01*
X821867Y-217472D01*
X820120D01*
X818155Y-218347D01*
X816627Y-219805D01*
X815535Y-221556D01*
X814662Y-224472D01*
X814443Y-227097D01*
X814880Y-229722D01*
X815535Y-231472D01*
X816845Y-233222D01*
X818374Y-234389D01*
X819902Y-234972D01*
X821430D01*
X822959Y-234389D01*
X824269Y-233514D01*
X825361Y-232348D01*
G01X837402Y-234972D02*
X835655Y-234680D01*
X834127Y-233514D01*
X832817Y-231764D01*
X831943Y-229722D01*
X831507Y-227389D01*
Y-225055D01*
X831943Y-222722D01*
X832817Y-220680D01*
X834127Y-218931D01*
X835655Y-217764D01*
X837402Y-217472D01*
X839148Y-217764D01*
X840677Y-218931D01*
X841987Y-220680D01*
X842861Y-222722D01*
X843297Y-225055D01*
Y-227389D01*
X842861Y-229722D01*
X841987Y-231764D01*
X840677Y-233514D01*
X839148Y-234680D01*
X837402Y-234972D01*
G01X849880D02*
Y-217472D01*
X859924Y-234972D01*
Y-217472D01*
G01X867380Y-234972D02*
Y-217472D01*
X877424Y-234972D01*
Y-217472D01*
G01X887282D02*
X892522D01*
G01X889902D02*
Y-234972D01*
G01X887282D02*
X892522D01*
G01X911769D02*
X903035D01*
Y-217472D01*
X911769D01*
G01X908275Y-225930D02*
X903035D01*
G01X937817Y-234972D02*
X946987Y-217472D01*
G01X937817D02*
X946987Y-234972D01*
G01X955317D02*
Y-217472D01*
G01X964487D02*
Y-234972D01*
G01Y-226222D02*
X955317D01*
G01X823849Y-189972D02*
Y-172472D01*
X828215D01*
X829962Y-173347D01*
X831272Y-174514D01*
X832364Y-176263D01*
X833237Y-178306D01*
X833455Y-181222D01*
X833237Y-184139D01*
X832364Y-186181D01*
X831272Y-187931D01*
X829962Y-189097D01*
X828215Y-189972D01*
X823849D01*
G01X842877Y-182097D02*
X849864D01*
X849209Y-180055D01*
X848117Y-178889D01*
X846589Y-178306D01*
X845060Y-178597D01*
X843750Y-179472D01*
X842877Y-181514D01*
X842440Y-183264D01*
Y-185014D01*
X842877Y-186764D01*
X843969Y-188514D01*
X845279Y-189680D01*
X846807Y-189972D01*
X848335Y-189389D01*
X849864Y-187639D01*
G01X860377Y-187931D02*
X861469Y-189097D01*
X862997Y-189972D01*
X864307D01*
X865617Y-189389D01*
X866490Y-188514D01*
X866927Y-187348D01*
X866709Y-185597D01*
X865835Y-184722D01*
X861905Y-182972D01*
X861032Y-180930D01*
X861469Y-179472D01*
X862342Y-178597D01*
X863652Y-178306D01*
X864962Y-178597D01*
X866272Y-179472D01*
G01X881152Y-178306D02*
Y-189972D01*
G01Y-173639D02*
X880715Y-173347D01*
Y-172764D01*
X881152Y-172472D01*
X881589Y-172764D01*
Y-173347D01*
X881152Y-173639D01*
G01X895595Y-194347D02*
X897124Y-195514D01*
X898870Y-195805D01*
X900398Y-195514D01*
X901709Y-194056D01*
X902582Y-192014D01*
Y-178306D01*
G01Y-180639D02*
X901709Y-179472D01*
X900398Y-178597D01*
X898870Y-178306D01*
X897124Y-178889D01*
X896032Y-180055D01*
X895158Y-182097D01*
X894722Y-184139D01*
X894940Y-185889D01*
X895814Y-187931D01*
X897124Y-189389D01*
X898870Y-189972D01*
X900180Y-189680D01*
X901709Y-188514D01*
X902582Y-187348D01*
G01X912440Y-189972D02*
Y-178306D01*
G01Y-181222D02*
X913314Y-179764D01*
X914624Y-178597D01*
X916370Y-178306D01*
X917898Y-178597D01*
X919209Y-179764D01*
X919864Y-181805D01*
Y-189972D01*
G01X930377Y-182097D02*
X937364D01*
X936709Y-180055D01*
X935617Y-178889D01*
X934089Y-178306D01*
X932560Y-178597D01*
X931250Y-179472D01*
X930377Y-181514D01*
X929940Y-183264D01*
Y-185014D01*
X930377Y-186764D01*
X931469Y-188514D01*
X932779Y-189680D01*
X934307Y-189972D01*
X935835Y-189389D01*
X937364Y-187639D01*
G01X948095Y-189972D02*
Y-178306D01*
G01Y-180639D02*
X949187Y-179472D01*
X950279Y-178597D01*
X951807Y-178306D01*
X952898Y-178597D01*
X954209Y-179472D01*
G01X994852Y-217472D02*
X993105Y-218055D01*
X991795Y-219514D01*
X990922Y-221263D01*
X990267Y-223597D01*
X990049Y-226222D01*
X990267Y-228847D01*
X990922Y-231181D01*
X991795Y-232931D01*
X993105Y-234389D01*
X994852Y-234972D01*
X996598Y-234389D01*
X997909Y-232931D01*
X998782Y-231181D01*
X999437Y-228847D01*
X999655Y-226222D01*
X999437Y-223597D01*
X998782Y-221263D01*
X997909Y-219514D01*
X996598Y-218055D01*
X994852Y-217472D01*
G01X1012352Y-234972D02*
X1013880Y-234680D01*
X1015627Y-233806D01*
X1016719Y-232348D01*
X1017155Y-230305D01*
X1016719Y-228264D01*
X1015409Y-226514D01*
X1013444Y-225639D01*
X1011260D01*
X1009950Y-225055D01*
X1008858Y-223597D01*
X1008422Y-221556D01*
X1009077Y-219514D01*
X1010605Y-218055D01*
X1012352Y-217472D01*
X1014098Y-218055D01*
X1015627Y-219514D01*
X1016282Y-221556D01*
X1015845Y-223597D01*
X1014754Y-225055D01*
X1013444Y-225639D01*
X1011260D01*
X1009295Y-226514D01*
X1007985Y-228264D01*
X1007549Y-230305D01*
X1007985Y-232348D01*
X1009077Y-233806D01*
X1010824Y-234680D01*
X1012352Y-234972D01*
G01X1025922Y-235555D02*
X1033782Y-217472D01*
G01X1043204Y-220389D02*
X1044514Y-218639D01*
X1046042Y-217764D01*
X1047789Y-217472D01*
X1049972Y-218055D01*
X1051500Y-219514D01*
X1051937Y-221263D01*
X1051719Y-223014D01*
X1050845Y-224472D01*
X1046479Y-227389D01*
X1044514Y-229430D01*
X1043204Y-232348D01*
X1042767Y-234972D01*
X1051937D01*
G01X1060049Y-232348D02*
X1061358Y-233806D01*
X1062887Y-234680D01*
X1064852Y-234972D01*
X1066817Y-234389D01*
X1068345Y-233222D01*
X1069437Y-231181D01*
X1069655Y-228847D01*
X1069219Y-226514D01*
X1068127Y-225055D01*
X1066598Y-223889D01*
X1065070Y-223597D01*
X1063542Y-223889D01*
X1061577Y-225055D01*
X1062232Y-217472D01*
X1068127D01*
G01X1078422Y-235555D02*
X1086282Y-217472D01*
G01X1095704Y-220389D02*
X1097014Y-218639D01*
X1098542Y-217764D01*
X1100289Y-217472D01*
X1102472Y-218055D01*
X1104000Y-219514D01*
X1104437Y-221263D01*
X1104219Y-223014D01*
X1103345Y-224472D01*
X1098979Y-227389D01*
X1097014Y-229430D01*
X1095704Y-232348D01*
X1095267Y-234972D01*
X1104437D01*
G01X1117352Y-217472D02*
X1115605Y-218055D01*
X1114295Y-219514D01*
X1113422Y-221263D01*
X1112767Y-223597D01*
X1112549Y-226222D01*
X1112767Y-228847D01*
X1113422Y-231181D01*
X1114295Y-232931D01*
X1115605Y-234389D01*
X1117352Y-234972D01*
X1119098Y-234389D01*
X1120409Y-232931D01*
X1121282Y-231181D01*
X1121937Y-228847D01*
X1122155Y-226222D01*
X1121937Y-223597D01*
X1121282Y-221263D01*
X1120409Y-219514D01*
X1119098Y-218055D01*
X1117352Y-217472D01*
G01X1134852Y-234972D02*
Y-217472D01*
X1132232Y-220972D01*
G01Y-234972D02*
X1137472D01*
G01X1148204Y-227681D02*
X1149732Y-225639D01*
X1151042Y-224472D01*
X1152789Y-223889D01*
X1154317Y-224472D01*
X1155409Y-225639D01*
X1156282Y-227389D01*
X1156500Y-229430D01*
X1156282Y-231181D01*
X1155409Y-232931D01*
X1154098Y-234389D01*
X1152570Y-234972D01*
X1150824Y-234389D01*
X1149295Y-232639D01*
X1148422Y-230014D01*
X1148204Y-227097D01*
X1148640Y-223306D01*
X1149295Y-221263D01*
X1150387Y-219222D01*
X1151915Y-217764D01*
X1153444Y-217472D01*
X1154972Y-218055D01*
X1156064Y-219514D01*
G01X1042549Y-189972D02*
Y-172472D01*
X1046915D01*
X1048662Y-173347D01*
X1049972Y-174514D01*
X1051064Y-176263D01*
X1051937Y-178306D01*
X1052155Y-181222D01*
X1051937Y-184139D01*
X1051064Y-186181D01*
X1049972Y-187931D01*
X1048662Y-189097D01*
X1046915Y-189972D01*
X1042549D01*
G01X1068782D02*
Y-178306D01*
G01Y-180347D02*
X1067909Y-179181D01*
X1066598Y-178597D01*
X1065070Y-178306D01*
X1063542Y-178889D01*
X1062232Y-180055D01*
X1061358Y-181805D01*
X1060922Y-184139D01*
X1061358Y-186472D01*
X1062232Y-188222D01*
X1063542Y-189389D01*
X1065070Y-189972D01*
X1066598Y-189680D01*
X1067909Y-188806D01*
X1068782Y-187639D01*
G01X1082352Y-172472D02*
Y-189972D01*
G01X1079295Y-178306D02*
X1085409D01*
G01X1096577Y-182097D02*
X1103564D01*
X1102909Y-180055D01*
X1101817Y-178889D01*
X1100289Y-178306D01*
X1098760Y-178597D01*
X1097450Y-179472D01*
X1096577Y-181514D01*
X1096140Y-183264D01*
Y-185014D01*
X1096577Y-186764D01*
X1097669Y-188514D01*
X1098979Y-189680D01*
X1100507Y-189972D01*
X1102035Y-189389D01*
X1103564Y-187639D01*
G01X20700Y30200D02*
X54200D01*
Y63300D01*
X9900D01*
Y30200D01*
X20700D01*
G01X15000Y64000D02*
Y92000D01*
X46500Y123500D01*
G01X12500Y68500D02*
X17500D01*
X15000Y66000D01*
X12500Y68500D01*
G01X26744Y89209D02*
X28511Y90977D01*
X29248Y90241D01*
X29395Y89916D01*
X29425Y89651D01*
X29248Y89357D01*
X28953Y89180D01*
X28629Y89209D01*
X28335Y89327D01*
X27598Y90064D01*
G01X28335Y89327D02*
X27922Y88031D01*
G01X29525Y86428D02*
X29761Y86251D01*
X30085Y86104D01*
X30379D01*
X30644Y86251D01*
X30792Y86516D01*
Y86870D01*
X30615Y87224D01*
X30320Y87518D01*
X30203Y87754D01*
X30202Y88049D01*
X30350Y88314D01*
X30644Y88432D01*
X30998Y88373D01*
X31293Y88196D01*
X31469Y87901D01*
X31528Y87548D01*
X31411Y87253D01*
X31145Y87106D01*
X30851D01*
X30615Y87224D01*
X30320Y87518D01*
X29967Y87695D01*
X29613D01*
X29348Y87548D01*
X29201Y87282D01*
Y86988D01*
X29348Y86664D01*
X29525Y86428D01*
G01X33485Y86004D02*
X33190Y86181D01*
X32866Y86210D01*
X32571Y86151D01*
X32247Y86004D01*
X31953Y85768D01*
X31717Y85474D01*
X31570Y85149D01*
X31511Y84855D01*
X31540Y84531D01*
X31717Y84236D01*
X32011Y84059D01*
X32336Y84030D01*
X32630Y84089D01*
X32954Y84236D01*
X33249Y84472D01*
X33485Y84766D01*
X33632Y85091D01*
X33691Y85385D01*
X33661Y85709D01*
X33485Y86004D01*
G01X26458Y90816D02*
X24690Y92583D01*
X25426Y93320D01*
X25751Y93467D01*
X26016Y93497D01*
X26310Y93320D01*
X26487Y93025D01*
X26458Y92701D01*
X26340Y92407D01*
X25603Y91670D01*
G01X26340Y92407D02*
X27636Y91994D01*
G01X29239Y93597D02*
X29416Y93833D01*
X29563Y94157D01*
Y94451D01*
X29416Y94716D01*
X29151Y94864D01*
X28797D01*
X28443Y94687D01*
X28149Y94392D01*
X27913Y94275D01*
X27618Y94274D01*
X27353Y94422D01*
X27235Y94716D01*
X27294Y95070D01*
X27471Y95365D01*
X27766Y95541D01*
X28119Y95600D01*
X28414Y95483D01*
X28561Y95217D01*
Y94923D01*
X28443Y94687D01*
X28149Y94392D01*
X27972Y94039D01*
Y93685D01*
X28119Y93420D01*
X28385Y93273D01*
X28679D01*
X29003Y93420D01*
X29239Y93597D01*
G01X30429Y95494D02*
X30812Y95465D01*
X31166Y95583D01*
X31460Y95818D01*
X31667Y96084D01*
X31755Y96467D01*
X31726Y96791D01*
X31578Y96997D01*
X31313Y97144D01*
X30959Y97085D01*
X30694Y96938D01*
X30429Y96673D01*
G01X30694Y96938D02*
X30783Y97203D01*
Y97498D01*
X30665Y97733D01*
X30429Y97851D01*
X30135D01*
X29781Y97675D01*
X29545Y97380D01*
X29398Y96997D01*
G01X21508Y40417D02*
X21383Y40167D01*
X21300Y39875D01*
Y39542D01*
X21425Y39167D01*
X21633Y38875D01*
X21883Y38667D01*
X22300Y38500D01*
X22675Y38458D01*
X23050Y38542D01*
X23300Y38667D01*
X23550Y38917D01*
X23717Y39208D01*
X23800Y39500D01*
Y39792D01*
X23717Y40083D01*
X23592Y40333D01*
X23425Y40542D01*
G01Y41683D02*
X23633Y41933D01*
X23758Y42225D01*
X23800Y42600D01*
X23717Y42975D01*
X23550Y43267D01*
X23258Y43475D01*
X22925Y43517D01*
X22592Y43433D01*
X22383Y43225D01*
X22217Y42933D01*
X22175Y42642D01*
X22217Y42350D01*
X22383Y41975D01*
X21300Y42100D01*
Y43225D01*
G01Y45700D02*
X21383Y45367D01*
X21592Y45117D01*
X21842Y44950D01*
X22175Y44825D01*
X22550Y44783D01*
X22925Y44825D01*
X23258Y44950D01*
X23508Y45117D01*
X23717Y45367D01*
X23800Y45700D01*
X23717Y46033D01*
X23508Y46283D01*
X23258Y46450D01*
X22925Y46575D01*
X22550Y46617D01*
X22175Y46575D01*
X21842Y46450D01*
X21592Y46283D01*
X21383Y46033D01*
X21300Y45700D01*
G01X22317Y36292D02*
X22067Y36417D01*
X21775Y36500D01*
X21442D01*
X21067Y36375D01*
X20775Y36167D01*
X20567Y35917D01*
X20400Y35500D01*
X20358Y35125D01*
X20442Y34750D01*
X20567Y34500D01*
X20817Y34250D01*
X21108Y34083D01*
X21400Y34000D01*
X21692D01*
X21983Y34083D01*
X22233Y34208D01*
X22442Y34375D01*
G01X23583D02*
X23833Y34167D01*
X24125Y34042D01*
X24500Y34000D01*
X24875Y34083D01*
X25167Y34250D01*
X25375Y34542D01*
X25417Y34875D01*
X25333Y35208D01*
X25125Y35417D01*
X24833Y35583D01*
X24542Y35625D01*
X24250Y35583D01*
X23875Y35417D01*
X24000Y36500D01*
X25125D01*
G01X26683Y34375D02*
X26933Y34167D01*
X27225Y34042D01*
X27600Y34000D01*
X27975Y34083D01*
X28267Y34250D01*
X28475Y34542D01*
X28517Y34875D01*
X28433Y35208D01*
X28225Y35417D01*
X27933Y35583D01*
X27642Y35625D01*
X27350Y35583D01*
X26975Y35417D01*
X27100Y36500D01*
X28225D01*
G01X22617Y58800D02*
Y61300D01*
X23658D01*
X23992Y61175D01*
X24200Y61008D01*
X24283Y60675D01*
X24200Y60342D01*
X23950Y60133D01*
X23658Y60008D01*
X22617D01*
G01X23658D02*
X24283Y58800D01*
G01X25633Y59300D02*
X25883Y59008D01*
X26217Y58842D01*
X26592Y58800D01*
X26925Y58842D01*
X27258Y59050D01*
X27467Y59300D01*
X27508Y59550D01*
X27425Y59842D01*
X27133Y60050D01*
X26842Y60133D01*
X26467D01*
G01X26842D02*
X27092Y60258D01*
X27300Y60467D01*
X27383Y60717D01*
X27300Y60967D01*
X27092Y61175D01*
X26717Y61300D01*
X26342Y61258D01*
X25967Y61092D01*
G01X15117Y58800D02*
Y61300D01*
X16158D01*
X16492Y61175D01*
X16700Y61008D01*
X16783Y60675D01*
X16700Y60342D01*
X16450Y60133D01*
X16158Y60008D01*
X15117D01*
G01X16158D02*
X16783Y58800D01*
G01X19550D02*
Y61300D01*
X18008Y59508D01*
X20092D01*
G01X27226Y49033D02*
X24726D01*
Y50074D01*
X24851Y50408D01*
X25018Y50616D01*
X25351Y50699D01*
X25684Y50616D01*
X25893Y50366D01*
X26018Y50074D01*
Y49033D01*
G01Y50074D02*
X27226Y50699D01*
G01X25143Y52174D02*
X24893Y52424D01*
X24768Y52716D01*
X24726Y53049D01*
X24809Y53466D01*
X25018Y53758D01*
X25268Y53841D01*
X25518Y53799D01*
X25726Y53633D01*
X26143Y52799D01*
X26434Y52424D01*
X26851Y52174D01*
X27226Y52091D01*
Y53841D01*
G01Y56066D02*
X27184Y56358D01*
X27059Y56691D01*
X26851Y56899D01*
X26559Y56983D01*
X26268Y56899D01*
X26018Y56649D01*
X25893Y56274D01*
Y55858D01*
X25809Y55608D01*
X25601Y55399D01*
X25309Y55316D01*
X25018Y55441D01*
X24809Y55733D01*
X24726Y56066D01*
X24809Y56399D01*
X25018Y56691D01*
X25309Y56816D01*
X25601Y56733D01*
X25809Y56524D01*
X25893Y56274D01*
Y55858D01*
X26018Y55483D01*
X26268Y55233D01*
X26559Y55149D01*
X26851Y55233D01*
X27059Y55441D01*
X27184Y55774D01*
X27226Y56066D01*
G01X23000Y48967D02*
X20500D01*
Y50008D01*
X20625Y50342D01*
X20792Y50550D01*
X21125Y50633D01*
X21458Y50550D01*
X21667Y50300D01*
X21792Y50008D01*
Y48967D01*
G01Y50008D02*
X23000Y50633D01*
G01X22625Y51983D02*
X22833Y52233D01*
X22958Y52525D01*
X23000Y52900D01*
X22917Y53275D01*
X22750Y53567D01*
X22458Y53775D01*
X22125Y53817D01*
X21792Y53733D01*
X21583Y53525D01*
X21417Y53233D01*
X21375Y52942D01*
X21417Y52650D01*
X21583Y52275D01*
X20500Y52400D01*
Y53525D01*
G01X23000Y56500D02*
X20500D01*
X22292Y54958D01*
Y57042D01*
G01X14800Y49067D02*
X12300D01*
Y50108D01*
X12425Y50442D01*
X12592Y50650D01*
X12925Y50733D01*
X13258Y50650D01*
X13467Y50400D01*
X13592Y50108D01*
Y49067D01*
G01Y50108D02*
X14800Y50733D01*
G01Y53000D02*
X12300D01*
X12800Y52500D01*
G01X14800D02*
Y53500D01*
G01X13758Y55308D02*
X13467Y55600D01*
X13300Y55850D01*
X13217Y56183D01*
X13300Y56475D01*
X13467Y56683D01*
X13717Y56850D01*
X14008Y56892D01*
X14258Y56850D01*
X14508Y56683D01*
X14717Y56433D01*
X14800Y56142D01*
X14717Y55808D01*
X14467Y55517D01*
X14092Y55350D01*
X13675Y55308D01*
X13133Y55392D01*
X12842Y55517D01*
X12550Y55725D01*
X12342Y56017D01*
X12300Y56308D01*
X12383Y56600D01*
X12592Y56808D01*
G01X18900Y48967D02*
X16400D01*
Y50008D01*
X16525Y50342D01*
X16692Y50550D01*
X17025Y50633D01*
X17358Y50550D01*
X17567Y50300D01*
X17692Y50008D01*
Y48967D01*
G01Y50008D02*
X18900Y50633D01*
G01Y52900D02*
X16400D01*
X16900Y52400D01*
G01X18900D02*
Y53400D01*
G01X18525Y55083D02*
X18733Y55333D01*
X18858Y55625D01*
X18900Y56000D01*
X18817Y56375D01*
X18650Y56667D01*
X18358Y56875D01*
X18025Y56917D01*
X17692Y56833D01*
X17483Y56625D01*
X17317Y56333D01*
X17275Y56042D01*
X17317Y55750D01*
X17483Y55375D01*
X16400Y55500D01*
Y56625D01*
G01X38500Y79100D02*
X25100D01*
G01Y71900D02*
X38500D01*
G01X25100Y79100D02*
Y71900D01*
G01X21205Y168239D02*
X22972Y170007D01*
X23709Y169271D01*
X23856Y168946D01*
X23886Y168681D01*
X23709Y168387D01*
X23414Y168210D01*
X23090Y168239D01*
X22796Y168357D01*
X22059Y169094D01*
G01X22796Y168357D02*
X22383Y167061D01*
G01X23986Y165458D02*
X24222Y165281D01*
X24546Y165134D01*
X24840D01*
X25105Y165281D01*
X25253Y165546D01*
Y165900D01*
X25076Y166254D01*
X24781Y166548D01*
X24664Y166784D01*
X24663Y167079D01*
X24811Y167344D01*
X25105Y167462D01*
X25459Y167403D01*
X25754Y167226D01*
X25930Y166931D01*
X25989Y166578D01*
X25872Y166283D01*
X25606Y166136D01*
X25312D01*
X25076Y166254D01*
X24781Y166548D01*
X24428Y166725D01*
X24074D01*
X23809Y166578D01*
X23662Y166312D01*
Y166018D01*
X23809Y165694D01*
X23986Y165458D01*
G01X26355Y164562D02*
X26767D01*
X27062Y164504D01*
X27356Y164327D01*
X27504Y164062D01*
X27533Y163796D01*
X27474Y163502D01*
X27297Y163266D01*
X27091Y163119D01*
X26797Y163060D01*
X26472Y163089D01*
X26207Y163237D01*
X26031Y163531D01*
X26001Y163914D01*
X26148Y164297D01*
X26414Y164621D01*
X26855Y164945D01*
X27150Y165063D01*
X27504Y165122D01*
X27857Y165063D01*
X28093Y164887D01*
X28240Y164621D01*
Y164327D01*
G01X25349Y169849D02*
X27116Y171617D01*
X27853Y170881D01*
X28000Y170556D01*
X28030Y170291D01*
X27853Y169997D01*
X27558Y169820D01*
X27234Y169849D01*
X26940Y169967D01*
X26203Y170704D01*
G01X26940Y169967D02*
X26527Y168671D01*
G01X28130Y167068D02*
X28366Y166891D01*
X28690Y166744D01*
X28984D01*
X29249Y166891D01*
X29397Y167156D01*
Y167510D01*
X29220Y167864D01*
X28925Y168158D01*
X28808Y168394D01*
X28807Y168689D01*
X28955Y168954D01*
X29249Y169072D01*
X29603Y169013D01*
X29898Y168836D01*
X30074Y168541D01*
X30133Y168188D01*
X30016Y167893D01*
X29750Y167746D01*
X29456D01*
X29220Y167864D01*
X28925Y168158D01*
X28572Y168335D01*
X28218D01*
X27953Y168188D01*
X27806Y167922D01*
Y167628D01*
X27953Y167304D01*
X28130Y167068D01*
G01X30263Y164935D02*
X30705Y165259D01*
X31117Y165495D01*
X31530Y165672D01*
X32001Y165848D01*
X32679Y166055D01*
X31500Y167233D01*
G01X20319Y169019D02*
X18551Y170786D01*
X19287Y171523D01*
X19612Y171670D01*
X19877Y171700D01*
X20171Y171523D01*
X20348Y171228D01*
X20319Y170904D01*
X20201Y170610D01*
X19464Y169873D01*
G01X20201Y170610D02*
X21497Y170197D01*
G01X22393Y171505D02*
X22746Y171564D01*
X23041Y171741D01*
X23218Y172036D01*
X23247Y172419D01*
X23129Y172831D01*
X22923Y173155D01*
X22599Y173479D01*
X22275Y173686D01*
X21892Y173774D01*
X21597Y173715D01*
X21332Y173568D01*
X21155Y173273D01*
X21096Y172978D01*
X21155Y172684D01*
X21332Y172389D01*
X21597Y172242D01*
X21951Y172183D01*
X22246Y172242D01*
X22481Y172419D01*
X22658Y172713D01*
X22687Y173037D01*
X22599Y173479D01*
G01X23524Y175760D02*
X23347Y175465D01*
X23318Y175141D01*
X23377Y174846D01*
X23524Y174522D01*
X23760Y174228D01*
X24054Y173992D01*
X24379Y173845D01*
X24673Y173786D01*
X24997Y173815D01*
X25292Y173992D01*
X25469Y174286D01*
X25498Y174611D01*
X25439Y174905D01*
X25292Y175229D01*
X25056Y175524D01*
X24762Y175760D01*
X24437Y175907D01*
X24143Y175966D01*
X23819Y175936D01*
X23524Y175760D01*
G01X15775Y160500D02*
Y163000D01*
G01X17525D02*
Y160500D01*
G01Y161750D02*
X15775D01*
G01X19750Y160500D02*
Y163000D01*
X19250Y162500D01*
G01Y160500D02*
X20250D01*
G01X22400Y214000D02*
Y211500D01*
G01X21442Y214000D02*
X23358D01*
G01X26417Y213792D02*
X26167Y213917D01*
X25875Y214000D01*
X25542D01*
X25167Y213875D01*
X24875Y213667D01*
X24667Y213417D01*
X24500Y213000D01*
X24458Y212625D01*
X24542Y212250D01*
X24667Y212000D01*
X24917Y211750D01*
X25208Y211583D01*
X25500Y211500D01*
X25792D01*
X26083Y211583D01*
X26333Y211708D01*
X26542Y211875D01*
G01X27808Y213583D02*
X28058Y213833D01*
X28350Y213958D01*
X28683Y214000D01*
X29100Y213917D01*
X29392Y213708D01*
X29475Y213458D01*
X29433Y213208D01*
X29267Y213000D01*
X28433Y212583D01*
X28058Y212292D01*
X27808Y211875D01*
X27725Y211500D01*
X29475D01*
G01X17250Y181900D02*
Y209900D01*
G01X48550Y181900D02*
X17250D01*
G01Y209900D02*
X48550D01*
G01X-19032Y356839D02*
X-18565Y357305D01*
X-18165Y357572D01*
X-17632Y357705D01*
X-17165Y357572D01*
X-16832Y357305D01*
X-16565Y356905D01*
X-16498Y356439D01*
X-16565Y356039D01*
X-16832Y355639D01*
X-17232Y355305D01*
X-17698Y355172D01*
X-18232Y355305D01*
X-18698Y355705D01*
X-18965Y356305D01*
X-19032Y356972D01*
X-18898Y357839D01*
X-18698Y358305D01*
X-18365Y358772D01*
X-17898Y359105D01*
X-17432Y359172D01*
X-16965Y359039D01*
X-16632Y358705D01*
G01X-19150Y387404D02*
X-18750Y387071D01*
X-18283Y386871D01*
X-17683Y386804D01*
X-17083Y386937D01*
X-16616Y387204D01*
X-16283Y387671D01*
X-16216Y388204D01*
X-16350Y388737D01*
X-16683Y389071D01*
X-17150Y389337D01*
X-17616Y389404D01*
X-18083Y389337D01*
X-18683Y389071D01*
X-18483Y390804D01*
X-16683D01*
G01X-15379Y417140D02*
Y421140D01*
X-17846Y418273D01*
X-14512D01*
G01X-18799Y450728D02*
X-18399Y450261D01*
X-17865Y449995D01*
X-17265Y449928D01*
X-16732Y449995D01*
X-16199Y450328D01*
X-15865Y450728D01*
X-15799Y451128D01*
X-15932Y451595D01*
X-16399Y451928D01*
X-16865Y452061D01*
X-17465D01*
G01X-16865D02*
X-16465Y452261D01*
X-16132Y452595D01*
X-15999Y452995D01*
X-16132Y453395D01*
X-16465Y453728D01*
X-17065Y453928D01*
X-17665Y453861D01*
X-18265Y453595D01*
G01X-18492Y484661D02*
X-18092Y485061D01*
X-17625Y485261D01*
X-17092Y485328D01*
X-16425Y485195D01*
X-15958Y484861D01*
X-15825Y484461D01*
X-15892Y484061D01*
X-16158Y483728D01*
X-17492Y483061D01*
X-18092Y482595D01*
X-18492Y481928D01*
X-18625Y481328D01*
X-15825D01*
G01X-17863Y512875D02*
Y516875D01*
X-18663Y516075D01*
G01Y512875D02*
X-17063D01*
G01X96450Y-48756D02*
X97283D01*
Y-49506D01*
X97033Y-49756D01*
X96742Y-49923D01*
X96325Y-50006D01*
X95908Y-49923D01*
X95617Y-49756D01*
X95367Y-49506D01*
X95200Y-49214D01*
X95117Y-48881D01*
Y-48589D01*
X95200Y-48339D01*
X95367Y-48048D01*
X95617Y-47798D01*
X95867Y-47631D01*
X96200Y-47506D01*
X96492D01*
X96825Y-47589D01*
X97075Y-47756D01*
G01X98508Y-50006D02*
Y-47506D01*
X100092D01*
G01X99508Y-48714D02*
X98508D01*
G01X101608Y-47923D02*
X101858Y-47673D01*
X102150Y-47548D01*
X102483Y-47506D01*
X102900Y-47589D01*
X103192Y-47798D01*
X103275Y-48048D01*
X103233Y-48298D01*
X103067Y-48506D01*
X102233Y-48923D01*
X101858Y-49214D01*
X101608Y-49631D01*
X101525Y-50006D01*
X103275D01*
G01X103200Y2817D02*
X100700D01*
Y3858D01*
X100825Y4192D01*
X100992Y4400D01*
X101325Y4483D01*
X101658Y4400D01*
X101867Y4150D01*
X101992Y3858D01*
Y2817D01*
G01Y3858D02*
X103200Y4483D01*
G01Y6750D02*
X100700D01*
X101200Y6250D01*
G01X103200D02*
Y7250D01*
G01X105300Y19800D02*
X101300D01*
Y12400D01*
G01X107900Y2467D02*
X105400D01*
Y3508D01*
X105525Y3842D01*
X105692Y4050D01*
X106025Y4133D01*
X106358Y4050D01*
X106567Y3800D01*
X106692Y3508D01*
Y2467D01*
G01Y3508D02*
X107900Y4133D01*
G01X107525Y5483D02*
X107733Y5733D01*
X107858Y6025D01*
X107900Y6400D01*
X107817Y6775D01*
X107650Y7067D01*
X107358Y7275D01*
X107025Y7317D01*
X106692Y7233D01*
X106483Y7025D01*
X106317Y6733D01*
X106275Y6442D01*
X106317Y6150D01*
X106483Y5775D01*
X105400Y5900D01*
Y7025D01*
G01X106858Y8708D02*
X106567Y9000D01*
X106400Y9250D01*
X106317Y9583D01*
X106400Y9875D01*
X106567Y10083D01*
X106817Y10250D01*
X107108Y10292D01*
X107358Y10250D01*
X107608Y10083D01*
X107817Y9833D01*
X107900Y9542D01*
X107817Y9208D01*
X107567Y8917D01*
X107192Y8750D01*
X106775Y8708D01*
X106233Y8792D01*
X105942Y8917D01*
X105650Y9125D01*
X105442Y9417D01*
X105400Y9708D01*
X105483Y10000D01*
X105692Y10208D01*
G01X109600Y19800D02*
X105600D01*
Y12400D01*
G01X98000Y-28883D02*
X95500D01*
Y-27842D01*
X95625Y-27508D01*
X95792Y-27300D01*
X96125Y-27217D01*
X96458Y-27300D01*
X96667Y-27550D01*
X96792Y-27842D01*
Y-28883D01*
G01Y-27842D02*
X98000Y-27217D01*
G01X95917Y-25742D02*
X95667Y-25492D01*
X95542Y-25200D01*
X95500Y-24867D01*
X95583Y-24450D01*
X95792Y-24158D01*
X96042Y-24075D01*
X96292Y-24117D01*
X96500Y-24283D01*
X96917Y-25117D01*
X97208Y-25492D01*
X97625Y-25742D01*
X98000Y-25825D01*
Y-24075D01*
G01X95500Y-21850D02*
X95583Y-22183D01*
X95792Y-22433D01*
X96042Y-22600D01*
X96375Y-22725D01*
X96750Y-22767D01*
X97125Y-22725D01*
X97458Y-22600D01*
X97708Y-22433D01*
X97917Y-22183D01*
X98000Y-21850D01*
X97917Y-21517D01*
X97708Y-21267D01*
X97458Y-21100D01*
X97125Y-20975D01*
X96750Y-20933D01*
X96375Y-20975D01*
X96042Y-21100D01*
X95792Y-21267D01*
X95583Y-21517D01*
X95500Y-21850D01*
G01X97500Y-19667D02*
X97792Y-19417D01*
X97958Y-19083D01*
X98000Y-18708D01*
X97958Y-18375D01*
X97750Y-18042D01*
X97500Y-17833D01*
X97250Y-17792D01*
X96958Y-17875D01*
X96750Y-18167D01*
X96667Y-18458D01*
Y-18833D01*
G01Y-18458D02*
X96542Y-18208D01*
X96333Y-18000D01*
X96083Y-17917D01*
X95833Y-18000D01*
X95625Y-18208D01*
X95500Y-18583D01*
X95542Y-18958D01*
X95708Y-19333D01*
G01X113200Y-29500D02*
X105200D01*
Y-11900D01*
X113200D01*
Y-29500D01*
G01X67600Y39967D02*
X65100D01*
Y40967D01*
X65225Y41300D01*
X65517Y41550D01*
X65850Y41633D01*
X66183Y41550D01*
X66433Y41342D01*
X66558Y40967D01*
Y39967D01*
G01X65308Y44817D02*
X65183Y44567D01*
X65100Y44275D01*
Y43942D01*
X65225Y43567D01*
X65433Y43275D01*
X65683Y43067D01*
X66100Y42900D01*
X66475Y42858D01*
X66850Y42942D01*
X67100Y43067D01*
X67350Y43317D01*
X67517Y43608D01*
X67600Y43900D01*
Y44192D01*
X67517Y44483D01*
X67392Y44733D01*
X67225Y44942D01*
G01Y46083D02*
X67433Y46333D01*
X67558Y46625D01*
X67600Y47000D01*
X67517Y47375D01*
X67350Y47667D01*
X67058Y47875D01*
X66725Y47917D01*
X66392Y47833D01*
X66183Y47625D01*
X66017Y47333D01*
X65975Y47042D01*
X66017Y46750D01*
X66183Y46375D01*
X65100Y46500D01*
Y47625D01*
G01X60267Y74200D02*
Y76700D01*
X61267D01*
X61600Y76575D01*
X61850Y76283D01*
X61933Y75950D01*
X61850Y75617D01*
X61642Y75367D01*
X61267Y75242D01*
X60267D01*
G01X65117Y76492D02*
X64867Y76617D01*
X64575Y76700D01*
X64242D01*
X63867Y76575D01*
X63575Y76367D01*
X63367Y76117D01*
X63200Y75700D01*
X63158Y75325D01*
X63242Y74950D01*
X63367Y74700D01*
X63617Y74450D01*
X63908Y74283D01*
X64200Y74200D01*
X64492D01*
X64783Y74283D01*
X65033Y74408D01*
X65242Y74575D01*
G01X66508Y76283D02*
X66758Y76533D01*
X67050Y76658D01*
X67383Y76700D01*
X67800Y76617D01*
X68092Y76408D01*
X68175Y76158D01*
X68133Y75908D01*
X67967Y75700D01*
X67133Y75283D01*
X66758Y74992D01*
X66508Y74575D01*
X66425Y74200D01*
X68175D01*
G01X45526Y97597D02*
X42697Y94769D01*
X47930Y89536D01*
G01X29627Y92092D02*
X31394Y93860D01*
X32131Y93124D01*
X32278Y92799D01*
X32308Y92534D01*
X32131Y92240D01*
X31836Y92063D01*
X31512Y92092D01*
X31218Y92210D01*
X30481Y92947D01*
G01X31218Y92210D02*
X30805Y90914D01*
G01X32408Y89311D02*
X32644Y89134D01*
X32968Y88987D01*
X33262D01*
X33527Y89134D01*
X33675Y89399D01*
Y89753D01*
X33498Y90107D01*
X33203Y90401D01*
X33086Y90637D01*
X33085Y90932D01*
X33233Y91197D01*
X33527Y91315D01*
X33881Y91256D01*
X34176Y91079D01*
X34352Y90784D01*
X34411Y90431D01*
X34294Y90136D01*
X34028Y89989D01*
X33734D01*
X33498Y90107D01*
X33203Y90401D01*
X32850Y90578D01*
X32496D01*
X32231Y90431D01*
X32084Y90165D01*
Y89871D01*
X32231Y89547D01*
X32408Y89311D01*
G01X34600Y87119D02*
X36368Y88887D01*
X35661D01*
G01X34246Y87473D02*
X34953Y86766D01*
G01X48409Y100481D02*
X45581Y97652D01*
X50814Y92420D01*
G01X40205Y92749D02*
X34549Y98406D01*
X46994Y110851D01*
X52651Y105194D01*
X40205Y92749D01*
G01X34536Y83376D02*
X34270Y83288D01*
X34005Y83141D01*
X33770Y82905D01*
X33593Y82551D01*
X33534Y82198D01*
X33563Y81874D01*
X33740Y81461D01*
X33976Y81167D01*
X34300Y80961D01*
X34565Y80872D01*
X34919D01*
X35243Y80961D01*
X35508Y81108D01*
X35714Y81314D01*
X35861Y81579D01*
X35950Y81844D01*
X35979Y82110D01*
G01X38053Y83653D02*
X36286Y85421D01*
X36462Y83064D01*
X37936Y84537D01*
G01X39833Y85433D02*
X39509Y85875D01*
X39273Y86287D01*
X39096Y86700D01*
X38920Y87171D01*
X38713Y87849D01*
X37535Y86670D01*
G01X84981Y64405D02*
X84856Y64155D01*
X84773Y63863D01*
Y63530D01*
X84898Y63155D01*
X85106Y62863D01*
X85356Y62655D01*
X85773Y62488D01*
X86148Y62446D01*
X86523Y62530D01*
X86773Y62655D01*
X87023Y62905D01*
X87190Y63196D01*
X87273Y63488D01*
Y63780D01*
X87190Y64071D01*
X87065Y64321D01*
X86898Y64530D01*
G01X86773Y65671D02*
X87065Y65921D01*
X87231Y66255D01*
X87273Y66630D01*
X87231Y66963D01*
X87023Y67296D01*
X86773Y67505D01*
X86523Y67546D01*
X86231Y67463D01*
X86023Y67171D01*
X85940Y66880D01*
Y66505D01*
G01Y66880D02*
X85815Y67130D01*
X85606Y67338D01*
X85356Y67421D01*
X85106Y67338D01*
X84898Y67130D01*
X84773Y66755D01*
X84815Y66380D01*
X84981Y66005D01*
G01X86773Y68771D02*
X87065Y69021D01*
X87231Y69355D01*
X87273Y69730D01*
X87231Y70063D01*
X87023Y70396D01*
X86773Y70605D01*
X86523Y70646D01*
X86231Y70563D01*
X86023Y70271D01*
X85940Y69980D01*
Y69605D01*
G01Y69980D02*
X85815Y70230D01*
X85606Y70438D01*
X85356Y70521D01*
X85106Y70438D01*
X84898Y70230D01*
X84773Y69855D01*
X84815Y69480D01*
X84981Y69105D01*
G01X38243Y31698D02*
Y34198D01*
X39284D01*
X39618Y34073D01*
X39826Y33906D01*
X39909Y33573D01*
X39826Y33240D01*
X39576Y33031D01*
X39284Y32906D01*
X38243D01*
G01X39284D02*
X39909Y31698D01*
G01X41468Y31990D02*
X41759Y31781D01*
X42093Y31698D01*
X42426Y31781D01*
X42718Y32031D01*
X42926Y32406D01*
X43009Y32781D01*
Y33240D01*
X42926Y33615D01*
X42718Y33948D01*
X42468Y34115D01*
X42176Y34198D01*
X41843Y34115D01*
X41593Y33948D01*
X41426Y33698D01*
X41343Y33365D01*
X41426Y33073D01*
X41634Y32781D01*
X41884Y32615D01*
X42176Y32573D01*
X42509Y32656D01*
X42759Y32865D01*
X43009Y33240D01*
G01X45276Y31698D02*
Y34198D01*
X44776Y33698D01*
G01Y31698D02*
X45776D01*
G01X38256Y35808D02*
Y38308D01*
X39297D01*
X39631Y38183D01*
X39839Y38016D01*
X39922Y37683D01*
X39839Y37350D01*
X39589Y37141D01*
X39297Y37016D01*
X38256D01*
G01X39297D02*
X39922Y35808D01*
G01X41481Y36100D02*
X41772Y35891D01*
X42106Y35808D01*
X42439Y35891D01*
X42731Y36141D01*
X42939Y36516D01*
X43022Y36891D01*
Y37350D01*
X42939Y37725D01*
X42731Y38058D01*
X42481Y38225D01*
X42189Y38308D01*
X41856Y38225D01*
X41606Y38058D01*
X41439Y37808D01*
X41356Y37475D01*
X41439Y37183D01*
X41647Y36891D01*
X41897Y36725D01*
X42189Y36683D01*
X42522Y36766D01*
X42772Y36975D01*
X43022Y37350D01*
G01X44497Y37891D02*
X44747Y38141D01*
X45039Y38266D01*
X45372Y38308D01*
X45789Y38225D01*
X46081Y38016D01*
X46164Y37766D01*
X46122Y37516D01*
X45956Y37308D01*
X45122Y36891D01*
X44747Y36600D01*
X44497Y36183D01*
X44414Y35808D01*
X46164D01*
G01X38252Y39936D02*
Y42436D01*
X39293D01*
X39627Y42311D01*
X39835Y42144D01*
X39918Y41811D01*
X39835Y41478D01*
X39585Y41269D01*
X39293Y41144D01*
X38252D01*
G01X39293D02*
X39918Y39936D01*
G01X41477Y40228D02*
X41768Y40019D01*
X42102Y39936D01*
X42435Y40019D01*
X42727Y40269D01*
X42935Y40644D01*
X43018Y41019D01*
Y41478D01*
X42935Y41853D01*
X42727Y42186D01*
X42477Y42353D01*
X42185Y42436D01*
X41852Y42353D01*
X41602Y42186D01*
X41435Y41936D01*
X41352Y41603D01*
X41435Y41311D01*
X41643Y41019D01*
X41893Y40853D01*
X42185Y40811D01*
X42518Y40894D01*
X42768Y41103D01*
X43018Y41478D01*
G01X44368Y40436D02*
X44618Y40144D01*
X44952Y39978D01*
X45327Y39936D01*
X45660Y39978D01*
X45993Y40186D01*
X46202Y40436D01*
X46243Y40686D01*
X46160Y40978D01*
X45868Y41186D01*
X45577Y41269D01*
X45202D01*
G01X45577D02*
X45827Y41394D01*
X46035Y41603D01*
X46118Y41853D01*
X46035Y42103D01*
X45827Y42311D01*
X45452Y42436D01*
X45077Y42394D01*
X44702Y42228D01*
G01X38022Y43959D02*
Y46459D01*
X39063D01*
X39397Y46334D01*
X39605Y46167D01*
X39688Y45834D01*
X39605Y45501D01*
X39355Y45292D01*
X39063Y45167D01*
X38022D01*
G01X39063D02*
X39688Y43959D01*
G01X41247Y44251D02*
X41538Y44042D01*
X41872Y43959D01*
X42205Y44042D01*
X42497Y44292D01*
X42705Y44667D01*
X42788Y45042D01*
Y45501D01*
X42705Y45876D01*
X42497Y46209D01*
X42247Y46376D01*
X41955Y46459D01*
X41622Y46376D01*
X41372Y46209D01*
X41205Y45959D01*
X41122Y45626D01*
X41205Y45334D01*
X41413Y45042D01*
X41663Y44876D01*
X41955Y44834D01*
X42288Y44917D01*
X42538Y45126D01*
X42788Y45501D01*
G01X45555Y43959D02*
Y46459D01*
X44013Y44667D01*
X46097D01*
G01X31304Y49015D02*
X28804D01*
Y50056D01*
X28929Y50390D01*
X29096Y50598D01*
X29429Y50681D01*
X29762Y50598D01*
X29971Y50348D01*
X30096Y50056D01*
Y49015D01*
G01Y50056D02*
X31304Y50681D01*
G01X29221Y52156D02*
X28971Y52406D01*
X28846Y52698D01*
X28804Y53031D01*
X28887Y53448D01*
X29096Y53740D01*
X29346Y53823D01*
X29596Y53781D01*
X29804Y53615D01*
X30221Y52781D01*
X30512Y52406D01*
X30929Y52156D01*
X31304Y52073D01*
Y53823D01*
G01X31012Y55340D02*
X31221Y55631D01*
X31304Y55965D01*
X31221Y56298D01*
X30971Y56590D01*
X30596Y56798D01*
X30221Y56881D01*
X29762D01*
X29387Y56798D01*
X29054Y56590D01*
X28887Y56340D01*
X28804Y56048D01*
X28887Y55715D01*
X29054Y55465D01*
X29304Y55298D01*
X29637Y55215D01*
X29929Y55298D01*
X30221Y55506D01*
X30387Y55756D01*
X30429Y56048D01*
X30346Y56381D01*
X30137Y56631D01*
X29762Y56881D01*
G01X95300Y54167D02*
X92800D01*
Y55208D01*
X92925Y55542D01*
X93092Y55750D01*
X93425Y55833D01*
X93758Y55750D01*
X93967Y55500D01*
X94092Y55208D01*
Y54167D01*
G01Y55208D02*
X95300Y55833D01*
G01Y58017D02*
X94758Y58100D01*
X94300Y58225D01*
X93883Y58392D01*
X93425Y58600D01*
X92800Y58933D01*
Y57267D01*
G01X95300Y61200D02*
X92800D01*
X93300Y60700D01*
G01X95300D02*
Y61700D01*
G01X96700Y55300D02*
X100700D01*
Y62700D01*
G01X98568Y74117D02*
Y76617D01*
X99609D01*
X99943Y76492D01*
X100151Y76325D01*
X100234Y75992D01*
X100151Y75659D01*
X99901Y75450D01*
X99609Y75325D01*
X98568D01*
G01X99609D02*
X100234Y74117D01*
G01X102418D02*
X102501Y74659D01*
X102626Y75117D01*
X102793Y75534D01*
X103001Y75992D01*
X103334Y76617D01*
X101668D01*
G01X105601Y74117D02*
X105893Y74159D01*
X106226Y74284D01*
X106434Y74492D01*
X106518Y74784D01*
X106434Y75075D01*
X106184Y75325D01*
X105809Y75450D01*
X105393D01*
X105143Y75534D01*
X104934Y75742D01*
X104851Y76034D01*
X104976Y76325D01*
X105268Y76534D01*
X105601Y76617D01*
X105934Y76534D01*
X106226Y76325D01*
X106351Y76034D01*
X106268Y75742D01*
X106059Y75534D01*
X105809Y75450D01*
X105393D01*
X105018Y75325D01*
X104768Y75075D01*
X104684Y74784D01*
X104768Y74492D01*
X104976Y74284D01*
X105309Y74159D01*
X105601Y74117D01*
G01X37739Y48307D02*
Y50807D01*
X38780D01*
X39114Y50682D01*
X39322Y50515D01*
X39405Y50182D01*
X39322Y49849D01*
X39072Y49640D01*
X38780Y49515D01*
X37739D01*
G01X38780D02*
X39405Y48307D01*
G01X41672D02*
X41964Y48349D01*
X42297Y48474D01*
X42505Y48682D01*
X42589Y48974D01*
X42505Y49265D01*
X42255Y49515D01*
X41880Y49640D01*
X41464D01*
X41214Y49724D01*
X41005Y49932D01*
X40922Y50224D01*
X41047Y50515D01*
X41339Y50724D01*
X41672Y50807D01*
X42005Y50724D01*
X42297Y50515D01*
X42422Y50224D01*
X42339Y49932D01*
X42130Y49724D01*
X41880Y49640D01*
X41464D01*
X41089Y49515D01*
X40839Y49265D01*
X40755Y48974D01*
X40839Y48682D01*
X41047Y48474D01*
X41380Y48349D01*
X41672Y48307D01*
G01X44772D02*
X45064Y48349D01*
X45397Y48474D01*
X45605Y48682D01*
X45689Y48974D01*
X45605Y49265D01*
X45355Y49515D01*
X44980Y49640D01*
X44564D01*
X44314Y49724D01*
X44105Y49932D01*
X44022Y50224D01*
X44147Y50515D01*
X44439Y50724D01*
X44772Y50807D01*
X45105Y50724D01*
X45397Y50515D01*
X45522Y50224D01*
X45439Y49932D01*
X45230Y49724D01*
X44980Y49640D01*
X44564D01*
X44189Y49515D01*
X43939Y49265D01*
X43855Y48974D01*
X43939Y48682D01*
X44147Y48474D01*
X44480Y48349D01*
X44772Y48307D01*
G01X37710Y52641D02*
Y55141D01*
X38751D01*
X39085Y55016D01*
X39293Y54849D01*
X39376Y54516D01*
X39293Y54183D01*
X39043Y53974D01*
X38751Y53849D01*
X37710D01*
G01X38751D02*
X39376Y52641D01*
G01X41643D02*
X41935Y52683D01*
X42268Y52808D01*
X42476Y53016D01*
X42560Y53308D01*
X42476Y53599D01*
X42226Y53849D01*
X41851Y53974D01*
X41435D01*
X41185Y54058D01*
X40976Y54266D01*
X40893Y54558D01*
X41018Y54849D01*
X41310Y55058D01*
X41643Y55141D01*
X41976Y55058D01*
X42268Y54849D01*
X42393Y54558D01*
X42310Y54266D01*
X42101Y54058D01*
X41851Y53974D01*
X41435D01*
X41060Y53849D01*
X40810Y53599D01*
X40726Y53308D01*
X40810Y53016D01*
X41018Y52808D01*
X41351Y52683D01*
X41643Y52641D01*
G01X44035Y52933D02*
X44326Y52724D01*
X44660Y52641D01*
X44993Y52724D01*
X45285Y52974D01*
X45493Y53349D01*
X45576Y53724D01*
Y54183D01*
X45493Y54558D01*
X45285Y54891D01*
X45035Y55058D01*
X44743Y55141D01*
X44410Y55058D01*
X44160Y54891D01*
X43993Y54641D01*
X43910Y54308D01*
X43993Y54016D01*
X44201Y53724D01*
X44451Y53558D01*
X44743Y53516D01*
X45076Y53599D01*
X45326Y53808D01*
X45576Y54183D01*
G01X106800Y43700D02*
X110800D01*
Y51100D01*
G01X36000Y49067D02*
X33500D01*
Y50108D01*
X33625Y50442D01*
X33792Y50650D01*
X34125Y50733D01*
X34458Y50650D01*
X34667Y50400D01*
X34792Y50108D01*
Y49067D01*
G01Y50108D02*
X36000Y50733D01*
G01X35625Y52083D02*
X35833Y52333D01*
X35958Y52625D01*
X36000Y53000D01*
X35917Y53375D01*
X35750Y53667D01*
X35458Y53875D01*
X35125Y53917D01*
X34792Y53833D01*
X34583Y53625D01*
X34417Y53333D01*
X34375Y53042D01*
X34417Y52750D01*
X34583Y52375D01*
X33500Y52500D01*
Y53625D01*
G01X35625Y55183D02*
X35833Y55433D01*
X35958Y55725D01*
X36000Y56100D01*
X35917Y56475D01*
X35750Y56767D01*
X35458Y56975D01*
X35125Y57017D01*
X34792Y56933D01*
X34583Y56725D01*
X34417Y56433D01*
X34375Y56142D01*
X34417Y55850D01*
X34583Y55475D01*
X33500Y55600D01*
Y56725D01*
G01X51100Y37717D02*
X48600D01*
Y38758D01*
X48725Y39092D01*
X48892Y39300D01*
X49225Y39383D01*
X49558Y39300D01*
X49767Y39050D01*
X49892Y38758D01*
Y37717D01*
G01Y38758D02*
X51100Y39383D01*
G01Y41650D02*
X48600D01*
X49100Y41150D01*
G01X51100D02*
Y42150D01*
G01Y44667D02*
X50558Y44750D01*
X50100Y44875D01*
X49683Y45042D01*
X49225Y45250D01*
X48600Y45583D01*
Y43917D01*
G01Y47850D02*
X48683Y47517D01*
X48892Y47267D01*
X49142Y47100D01*
X49475Y46975D01*
X49850Y46933D01*
X50225Y46975D01*
X50558Y47100D01*
X50808Y47267D01*
X51017Y47517D01*
X51100Y47850D01*
X51017Y48183D01*
X50808Y48433D01*
X50558Y48600D01*
X50225Y48725D01*
X49850Y48767D01*
X49475Y48725D01*
X49142Y48600D01*
X48892Y48433D01*
X48683Y48183D01*
X48600Y47850D01*
G01X63469Y51024D02*
Y53524D01*
X64510D01*
X64844Y53399D01*
X65052Y53232D01*
X65135Y52899D01*
X65052Y52566D01*
X64802Y52357D01*
X64510Y52232D01*
X63469D01*
G01X64510D02*
X65135Y51024D01*
G01X67402D02*
Y53524D01*
X66902Y53024D01*
G01Y51024D02*
X67902D01*
G01X69585Y51399D02*
X69835Y51191D01*
X70127Y51066D01*
X70502Y51024D01*
X70877Y51107D01*
X71169Y51274D01*
X71377Y51566D01*
X71419Y51899D01*
X71335Y52232D01*
X71127Y52441D01*
X70835Y52607D01*
X70544Y52649D01*
X70252Y52607D01*
X69877Y52441D01*
X70002Y53524D01*
X71127D01*
G01X72685Y51524D02*
X72935Y51232D01*
X73269Y51066D01*
X73644Y51024D01*
X73977Y51066D01*
X74310Y51274D01*
X74519Y51524D01*
X74560Y51774D01*
X74477Y52066D01*
X74185Y52274D01*
X73894Y52357D01*
X73519D01*
G01X73894D02*
X74144Y52482D01*
X74352Y52691D01*
X74435Y52941D01*
X74352Y53191D01*
X74144Y53399D01*
X73769Y53524D01*
X73394Y53482D01*
X73019Y53316D01*
G01X97500Y54600D02*
Y50600D01*
X104900D01*
G01X91972Y64750D02*
X93764D01*
X94139Y64917D01*
X94389Y65250D01*
X94472Y65667D01*
X94389Y66084D01*
X94139Y66417D01*
X93764Y66584D01*
X91972D01*
G01X94472Y68767D02*
X94430Y69059D01*
X94305Y69392D01*
X94097Y69600D01*
X93805Y69684D01*
X93514Y69600D01*
X93264Y69350D01*
X93139Y68975D01*
Y68559D01*
X93055Y68309D01*
X92847Y68100D01*
X92555Y68017D01*
X92264Y68142D01*
X92055Y68434D01*
X91972Y68767D01*
X92055Y69100D01*
X92264Y69392D01*
X92555Y69517D01*
X92847Y69434D01*
X93055Y69225D01*
X93139Y68975D01*
Y68559D01*
X93264Y68184D01*
X93514Y67934D01*
X93805Y67850D01*
X94097Y67934D01*
X94305Y68142D01*
X94430Y68475D01*
X94472Y68767D01*
G01X105600Y69400D02*
X115600D01*
G01X105600Y56000D02*
Y69400D01*
G01X115600Y56000D02*
X105600D01*
G01X95960Y63716D02*
X97752D01*
X98127Y63883D01*
X98377Y64216D01*
X98460Y64633D01*
X98377Y65050D01*
X98127Y65383D01*
X97752Y65550D01*
X95960D01*
G01X98460Y67733D02*
X95960D01*
X96460Y67233D01*
G01X98460D02*
Y68233D01*
G01X95960Y70833D02*
X96043Y70500D01*
X96252Y70250D01*
X96502Y70083D01*
X96835Y69958D01*
X97210Y69916D01*
X97585Y69958D01*
X97918Y70083D01*
X98168Y70250D01*
X98377Y70500D01*
X98460Y70833D01*
X98377Y71166D01*
X98168Y71416D01*
X97918Y71583D01*
X97585Y71708D01*
X97210Y71750D01*
X96835Y71708D01*
X96502Y71583D01*
X96252Y71416D01*
X96043Y71166D01*
X95960Y70833D01*
G01X95669Y93743D02*
X92669D01*
G01X105701Y83758D02*
Y81758D01*
G01X94775Y87864D02*
Y82864D01*
X99775D01*
G01Y102664D02*
X94775D01*
Y97664D01*
G01X32000Y36983D02*
X33792D01*
X34167Y37150D01*
X34417Y37483D01*
X34500Y37900D01*
X34417Y38317D01*
X34167Y38650D01*
X33792Y38817D01*
X32000D01*
G01X34500Y41000D02*
X32000D01*
X32500Y40500D01*
G01X34500D02*
Y41500D01*
G01X34125Y43183D02*
X34333Y43433D01*
X34458Y43725D01*
X34500Y44100D01*
X34417Y44475D01*
X34250Y44767D01*
X33958Y44975D01*
X33625Y45017D01*
X33292Y44933D01*
X33083Y44725D01*
X32917Y44433D01*
X32875Y44142D01*
X32917Y43850D01*
X33083Y43475D01*
X32000Y43600D01*
Y44725D01*
G01X85000Y92850D02*
X57000D01*
G01X85000Y124150D02*
Y92850D01*
G01X57000D02*
Y124150D01*
G01X70500Y27017D02*
X68000D01*
Y28058D01*
X68125Y28392D01*
X68292Y28600D01*
X68625Y28683D01*
X68958Y28600D01*
X69167Y28350D01*
X69292Y28058D01*
Y27017D01*
G01Y28058D02*
X70500Y28683D01*
G01X68417Y30158D02*
X68167Y30408D01*
X68042Y30700D01*
X68000Y31033D01*
X68083Y31450D01*
X68292Y31742D01*
X68542Y31825D01*
X68792Y31783D01*
X69000Y31617D01*
X69417Y30783D01*
X69708Y30408D01*
X70125Y30158D01*
X70500Y30075D01*
Y31825D01*
G01X68000Y34050D02*
X68083Y33717D01*
X68292Y33467D01*
X68542Y33300D01*
X68875Y33175D01*
X69250Y33133D01*
X69625Y33175D01*
X69958Y33300D01*
X70208Y33467D01*
X70417Y33717D01*
X70500Y34050D01*
X70417Y34383D01*
X70208Y34633D01*
X69958Y34800D01*
X69625Y34925D01*
X69250Y34967D01*
X68875Y34925D01*
X68542Y34800D01*
X68292Y34633D01*
X68083Y34383D01*
X68000Y34050D01*
G01X70500Y37650D02*
X68000D01*
X69792Y36108D01*
Y38192D01*
G01X89400Y30400D02*
Y38400D01*
X107000D01*
Y30400D01*
X89400D01*
G01X27467Y66100D02*
Y68600D01*
X28467D01*
X28800Y68475D01*
X29050Y68183D01*
X29133Y67850D01*
X29050Y67517D01*
X28842Y67267D01*
X28467Y67142D01*
X27467D01*
G01X30567Y68600D02*
Y66100D01*
X32233D01*
G01X34500D02*
Y68600D01*
X34000Y68100D01*
G01Y66100D02*
X35000D01*
G01X38500Y71900D02*
Y79100D01*
G01X53500Y157500D02*
Y164500D01*
X64000D01*
Y165500D01*
G01X67000Y168000D02*
X81000D01*
G01X94000Y156500D02*
X107000D01*
Y148000D01*
G01Y138500D02*
Y129500D01*
X101000D01*
G01X91000Y129000D02*
X88000D01*
G01X56000Y123500D02*
X47500D01*
X46500D01*
Y129500D01*
Y138000D01*
X58000D01*
Y144500D01*
X61000D01*
Y150500D01*
X58000D01*
G01X99286Y120550D02*
X99161Y120300D01*
X99078Y120008D01*
Y119675D01*
X99203Y119300D01*
X99411Y119008D01*
X99661Y118800D01*
X100078Y118633D01*
X100453Y118591D01*
X100828Y118675D01*
X101078Y118800D01*
X101328Y119050D01*
X101495Y119341D01*
X101578Y119633D01*
Y119925D01*
X101495Y120216D01*
X101370Y120466D01*
X101203Y120675D01*
G01X101578Y122733D02*
X99078D01*
X99578Y122233D01*
G01X101578D02*
Y123233D01*
G01X101203Y124916D02*
X101411Y125166D01*
X101536Y125458D01*
X101578Y125833D01*
X101495Y126208D01*
X101328Y126500D01*
X101036Y126708D01*
X100703Y126750D01*
X100370Y126666D01*
X100161Y126458D01*
X99995Y126166D01*
X99953Y125875D01*
X99995Y125583D01*
X100161Y125208D01*
X99078Y125333D01*
Y126458D01*
G01X104376Y120605D02*
X104251Y120355D01*
X104168Y120063D01*
Y119730D01*
X104293Y119355D01*
X104501Y119063D01*
X104751Y118855D01*
X105168Y118688D01*
X105543Y118646D01*
X105918Y118730D01*
X106168Y118855D01*
X106418Y119105D01*
X106585Y119396D01*
X106668Y119688D01*
Y119980D01*
X106585Y120271D01*
X106460Y120521D01*
X106293Y120730D01*
G01X106668Y122788D02*
X104168D01*
X104668Y122288D01*
G01X106668D02*
Y123288D01*
G01X105626Y125096D02*
X105335Y125388D01*
X105168Y125638D01*
X105085Y125971D01*
X105168Y126263D01*
X105335Y126471D01*
X105585Y126638D01*
X105876Y126680D01*
X106126Y126638D01*
X106376Y126471D01*
X106585Y126221D01*
X106668Y125930D01*
X106585Y125596D01*
X106335Y125305D01*
X105960Y125138D01*
X105543Y125096D01*
X105001Y125180D01*
X104710Y125305D01*
X104418Y125513D01*
X104210Y125805D01*
X104168Y126096D01*
X104251Y126388D01*
X104460Y126596D01*
G01X46287Y154628D02*
X43458Y151799D01*
X48691Y146567D01*
G01X49131Y157537D02*
X46303Y154709D01*
X51535Y149476D01*
G01X38727Y149148D02*
X33070Y154805D01*
X45515Y167250D01*
X51172Y161593D01*
X38727Y149148D01*
G01X30036Y160776D02*
X29770Y160688D01*
X29505Y160541D01*
X29270Y160305D01*
X29093Y159951D01*
X29034Y159598D01*
X29063Y159274D01*
X29240Y158861D01*
X29476Y158567D01*
X29800Y158361D01*
X30065Y158272D01*
X30419D01*
X30743Y158361D01*
X31008Y158508D01*
X31214Y158714D01*
X31361Y158979D01*
X31450Y159244D01*
X31479Y159510D01*
G01X33553Y161053D02*
X31786Y162821D01*
X31962Y160464D01*
X33436Y161937D01*
G01X34685Y162597D02*
X35038Y162656D01*
X35333Y162833D01*
X35510Y163128D01*
X35539Y163511D01*
X35421Y163923D01*
X35215Y164247D01*
X34891Y164571D01*
X34567Y164778D01*
X34184Y164866D01*
X33889Y164807D01*
X33624Y164660D01*
X33447Y164365D01*
X33388Y164070D01*
X33447Y163776D01*
X33624Y163481D01*
X33889Y163334D01*
X34243Y163275D01*
X34538Y163334D01*
X34773Y163511D01*
X34950Y163805D01*
X34979Y164129D01*
X34891Y164571D01*
G01X80700Y161800D02*
Y165800D01*
X73300D01*
G01X92700Y160017D02*
X90200D01*
Y161058D01*
X90325Y161392D01*
X90492Y161600D01*
X90825Y161683D01*
X91158Y161600D01*
X91367Y161350D01*
X91492Y161058D01*
Y160017D01*
G01Y161058D02*
X92700Y161683D01*
G01X92325Y163033D02*
X92533Y163283D01*
X92658Y163575D01*
X92700Y163950D01*
X92617Y164325D01*
X92450Y164617D01*
X92158Y164825D01*
X91825Y164867D01*
X91492Y164783D01*
X91283Y164575D01*
X91117Y164283D01*
X91075Y163992D01*
X91117Y163700D01*
X91283Y163325D01*
X90200Y163450D01*
Y164575D01*
G01X97700Y174300D02*
X93700D01*
Y166900D01*
G01X65800Y165800D02*
Y161800D01*
X73200D01*
G01X113765Y103330D02*
Y107330D01*
X106365D01*
G01X100076Y129798D02*
Y133798D01*
X92676D01*
G01X92689Y137908D02*
Y133908D01*
X100089D01*
G01X92685Y142036D02*
Y138036D01*
X100085D01*
G01X101355Y142059D02*
Y146059D01*
X93955D01*
G01X73726Y161166D02*
X69726D01*
Y153766D01*
G01X77804Y161148D02*
X73804D01*
Y153748D01*
G01X104017Y172312D02*
Y174812D01*
X105058D01*
X105392Y174687D01*
X105600Y174520D01*
X105683Y174187D01*
X105600Y173854D01*
X105350Y173645D01*
X105058Y173520D01*
X104017D01*
G01X105058D02*
X105683Y172312D01*
G01X107033Y172812D02*
X107283Y172520D01*
X107617Y172354D01*
X107992Y172312D01*
X108325Y172354D01*
X108658Y172562D01*
X108867Y172812D01*
X108908Y173062D01*
X108825Y173354D01*
X108533Y173562D01*
X108242Y173645D01*
X107867D01*
G01X108242D02*
X108492Y173770D01*
X108700Y173979D01*
X108783Y174229D01*
X108700Y174479D01*
X108492Y174687D01*
X108117Y174812D01*
X107742Y174770D01*
X107367Y174604D01*
G01X110133Y172812D02*
X110383Y172520D01*
X110717Y172354D01*
X111092Y172312D01*
X111425Y172354D01*
X111758Y172562D01*
X111967Y172812D01*
X112008Y173062D01*
X111925Y173354D01*
X111633Y173562D01*
X111342Y173645D01*
X110967D01*
G01X111342D02*
X111592Y173770D01*
X111800Y173979D01*
X111883Y174229D01*
X111800Y174479D01*
X111592Y174687D01*
X111217Y174812D01*
X110842Y174770D01*
X110467Y174604D01*
G01X100250Y166312D02*
Y162312D01*
X107650D01*
G01X104017Y176512D02*
Y179012D01*
X105058D01*
X105392Y178887D01*
X105600Y178720D01*
X105683Y178387D01*
X105600Y178054D01*
X105350Y177845D01*
X105058Y177720D01*
X104017D01*
G01X105058D02*
X105683Y176512D01*
G01X107033Y177012D02*
X107283Y176720D01*
X107617Y176554D01*
X107992Y176512D01*
X108325Y176554D01*
X108658Y176762D01*
X108867Y177012D01*
X108908Y177262D01*
X108825Y177554D01*
X108533Y177762D01*
X108242Y177845D01*
X107867D01*
G01X108242D02*
X108492Y177970D01*
X108700Y178179D01*
X108783Y178429D01*
X108700Y178679D01*
X108492Y178887D01*
X108117Y179012D01*
X107742Y178970D01*
X107367Y178804D01*
G01X111550Y176512D02*
Y179012D01*
X110008Y177220D01*
X112092D01*
G01X100250Y170512D02*
Y166512D01*
X107650D01*
G01X101500Y174067D02*
X99000D01*
Y175108D01*
X99125Y175442D01*
X99292Y175650D01*
X99625Y175733D01*
X99958Y175650D01*
X100167Y175400D01*
X100292Y175108D01*
Y174067D01*
G01Y175108D02*
X101500Y175733D01*
G01X100458Y177208D02*
X100167Y177500D01*
X100000Y177750D01*
X99917Y178083D01*
X100000Y178375D01*
X100167Y178583D01*
X100417Y178750D01*
X100708Y178792D01*
X100958Y178750D01*
X101208Y178583D01*
X101417Y178333D01*
X101500Y178042D01*
X101417Y177708D01*
X101167Y177417D01*
X100792Y177250D01*
X100375Y177208D01*
X99833Y177292D01*
X99542Y177417D01*
X99250Y177625D01*
X99042Y177917D01*
X99000Y178208D01*
X99083Y178500D01*
X99292Y178708D01*
G01X99000Y181100D02*
X99083Y180767D01*
X99292Y180517D01*
X99542Y180350D01*
X99875Y180225D01*
X100250Y180183D01*
X100625Y180225D01*
X100958Y180350D01*
X101208Y180517D01*
X101417Y180767D01*
X101500Y181100D01*
X101417Y181433D01*
X101208Y181683D01*
X100958Y181850D01*
X100625Y181975D01*
X100250Y182017D01*
X99875Y181975D01*
X99542Y181850D01*
X99292Y181683D01*
X99083Y181433D01*
X99000Y181100D01*
G01X93700Y174400D02*
X97700D01*
Y181800D01*
G01X95672Y150907D02*
Y146907D01*
X103072D01*
G01X95643Y155241D02*
Y151241D01*
X103043D01*
G01X101617Y158000D02*
Y160500D01*
X102658D01*
X102992Y160375D01*
X103200Y160208D01*
X103283Y159875D01*
X103200Y159542D01*
X102950Y159333D01*
X102658Y159208D01*
X101617D01*
G01X102658D02*
X103283Y158000D01*
G01X104758Y159042D02*
X105050Y159333D01*
X105300Y159500D01*
X105633Y159583D01*
X105925Y159500D01*
X106133Y159333D01*
X106300Y159083D01*
X106342Y158792D01*
X106300Y158542D01*
X106133Y158292D01*
X105883Y158083D01*
X105592Y158000D01*
X105258Y158083D01*
X104967Y158333D01*
X104800Y158708D01*
X104758Y159125D01*
X104842Y159667D01*
X104967Y159958D01*
X105175Y160250D01*
X105467Y160458D01*
X105758Y160500D01*
X106050Y160417D01*
X106258Y160208D01*
G01X93700Y159400D02*
X97700D01*
Y166800D01*
G01X85300Y163900D02*
X81300D01*
Y156500D01*
G01X69500Y159600D02*
X65500D01*
Y152200D01*
G01X35567Y176100D02*
Y178600D01*
X36608D01*
X36942Y178475D01*
X37150Y178308D01*
X37233Y177975D01*
X37150Y177642D01*
X36900Y177433D01*
X36608Y177308D01*
X35567D01*
G01X36608D02*
X37233Y176100D01*
G01X39500D02*
Y178600D01*
X39000Y178100D01*
G01Y176100D02*
X40000D01*
G01X42517D02*
X42600Y176642D01*
X42725Y177100D01*
X42892Y177517D01*
X43100Y177975D01*
X43433Y178600D01*
X41767D01*
G01X61300Y174800D02*
Y178800D01*
X53900D01*
G01X57300Y152300D02*
X61300D01*
Y159700D01*
G01X65400Y159600D02*
X61400D01*
Y152200D01*
G01X35465Y172100D02*
Y174600D01*
X36506D01*
X36840Y174475D01*
X37048Y174308D01*
X37131Y173975D01*
X37048Y173642D01*
X36798Y173433D01*
X36506Y173308D01*
X35465D01*
G01X36506D02*
X37131Y172100D01*
G01X39398D02*
Y174600D01*
X38898Y174100D01*
G01Y172100D02*
X39898D01*
G01X42998D02*
Y174600D01*
X41456Y172808D01*
X43540D01*
G01X61698Y170400D02*
Y174400D01*
X54298D01*
G01X35467Y168000D02*
Y170500D01*
X36508D01*
X36842Y170375D01*
X37050Y170208D01*
X37133Y169875D01*
X37050Y169542D01*
X36800Y169333D01*
X36508Y169208D01*
X35467D01*
G01X36508D02*
X37133Y168000D01*
G01X39400D02*
Y170500D01*
X38900Y170000D01*
G01Y168000D02*
X39900D01*
G01X41583Y168500D02*
X41833Y168208D01*
X42167Y168042D01*
X42542Y168000D01*
X42875Y168042D01*
X43208Y168250D01*
X43417Y168500D01*
X43458Y168750D01*
X43375Y169042D01*
X43083Y169250D01*
X42792Y169333D01*
X42417D01*
G01X42792D02*
X43042Y169458D01*
X43250Y169667D01*
X43333Y169917D01*
X43250Y170167D01*
X43042Y170375D01*
X42667Y170500D01*
X42292Y170458D01*
X41917Y170292D01*
G01X54300Y170300D02*
Y166300D01*
X61700D01*
G01X107218Y146658D02*
X103218D01*
Y139258D01*
G01X82533Y169000D02*
Y167208D01*
X82700Y166833D01*
X83033Y166583D01*
X83450Y166500D01*
X83867Y166583D01*
X84200Y166833D01*
X84367Y167208D01*
Y169000D01*
G01X86550Y166500D02*
Y169000D01*
X86050Y168500D01*
G01Y166500D02*
X87050D01*
G01X70173Y141266D02*
X67173D01*
G01X80205Y131281D02*
Y129281D01*
G01X82145Y149293D02*
Y151293D01*
G01X89079Y145187D02*
Y150187D01*
X84079D01*
G01X69279Y135387D02*
Y130387D01*
X74279D01*
G01Y150187D02*
X69279D01*
Y145187D01*
G01X49700Y114700D02*
X52200D01*
G01X49700Y113742D02*
Y115658D01*
G01X49908Y118717D02*
X49783Y118467D01*
X49700Y118175D01*
Y117842D01*
X49825Y117467D01*
X50033Y117175D01*
X50283Y116967D01*
X50700Y116800D01*
X51075Y116758D01*
X51450Y116842D01*
X51700Y116967D01*
X51950Y117217D01*
X52117Y117508D01*
X52200Y117800D01*
Y118092D01*
X52117Y118383D01*
X51992Y118633D01*
X51825Y118842D01*
G01X51700Y119983D02*
X51992Y120233D01*
X52158Y120567D01*
X52200Y120942D01*
X52158Y121275D01*
X51950Y121608D01*
X51700Y121817D01*
X51450Y121858D01*
X51158Y121775D01*
X50950Y121483D01*
X50867Y121192D01*
Y120817D01*
G01Y121192D02*
X50742Y121442D01*
X50533Y121650D01*
X50283Y121733D01*
X50033Y121650D01*
X49825Y121442D01*
X49700Y121067D01*
X49742Y120692D01*
X49908Y120317D01*
G01X81000Y128150D02*
X85000Y124150D01*
G01X61000Y128150D02*
X81000D01*
G01X57000Y124150D02*
X61000Y128150D01*
G01X76707Y230541D02*
X76582Y230291D01*
X76499Y229999D01*
Y229666D01*
X76624Y229291D01*
X76832Y228999D01*
X77082Y228791D01*
X77499Y228624D01*
X77874Y228582D01*
X78249Y228666D01*
X78499Y228791D01*
X78749Y229041D01*
X78916Y229332D01*
X78999Y229624D01*
Y229916D01*
X78916Y230207D01*
X78791Y230457D01*
X78624Y230666D01*
G01X76916Y231932D02*
X76666Y232182D01*
X76541Y232474D01*
X76499Y232807D01*
X76582Y233224D01*
X76791Y233516D01*
X77041Y233599D01*
X77291Y233557D01*
X77499Y233391D01*
X77916Y232557D01*
X78207Y232182D01*
X78624Y231932D01*
X78999Y231849D01*
Y233599D01*
G01X78624Y234907D02*
X78832Y235157D01*
X78957Y235449D01*
X78999Y235824D01*
X78916Y236199D01*
X78749Y236491D01*
X78457Y236699D01*
X78124Y236741D01*
X77791Y236657D01*
X77582Y236449D01*
X77416Y236157D01*
X77374Y235866D01*
X77416Y235574D01*
X77582Y235199D01*
X76499Y235324D01*
Y236449D01*
G01X67095Y230643D02*
X66970Y230393D01*
X66887Y230101D01*
Y229768D01*
X67012Y229393D01*
X67220Y229101D01*
X67470Y228893D01*
X67887Y228726D01*
X68262Y228684D01*
X68637Y228768D01*
X68887Y228893D01*
X69137Y229143D01*
X69304Y229434D01*
X69387Y229726D01*
Y230018D01*
X69304Y230309D01*
X69179Y230559D01*
X69012Y230768D01*
G01X67304Y232034D02*
X67054Y232284D01*
X66929Y232576D01*
X66887Y232909D01*
X66970Y233326D01*
X67179Y233618D01*
X67429Y233701D01*
X67679Y233659D01*
X67887Y233493D01*
X68304Y232659D01*
X68595Y232284D01*
X69012Y232034D01*
X69387Y231951D01*
Y233701D01*
G01Y235926D02*
X69345Y236218D01*
X69220Y236551D01*
X69012Y236759D01*
X68720Y236843D01*
X68429Y236759D01*
X68179Y236509D01*
X68054Y236134D01*
Y235718D01*
X67970Y235468D01*
X67762Y235259D01*
X67470Y235176D01*
X67179Y235301D01*
X66970Y235593D01*
X66887Y235926D01*
X66970Y236259D01*
X67179Y236551D01*
X67470Y236676D01*
X67762Y236593D01*
X67970Y236384D01*
X68054Y236134D01*
Y235718D01*
X68179Y235343D01*
X68429Y235093D01*
X68720Y235009D01*
X69012Y235093D01*
X69220Y235301D01*
X69345Y235634D01*
X69387Y235926D01*
G01X71948Y230528D02*
X71823Y230278D01*
X71740Y229986D01*
Y229653D01*
X71865Y229278D01*
X72073Y228986D01*
X72323Y228778D01*
X72740Y228611D01*
X73115Y228569D01*
X73490Y228653D01*
X73740Y228778D01*
X73990Y229028D01*
X74157Y229319D01*
X74240Y229611D01*
Y229903D01*
X74157Y230194D01*
X74032Y230444D01*
X73865Y230653D01*
G01X72157Y231919D02*
X71907Y232169D01*
X71782Y232461D01*
X71740Y232794D01*
X71823Y233211D01*
X72032Y233503D01*
X72282Y233586D01*
X72532Y233544D01*
X72740Y233378D01*
X73157Y232544D01*
X73448Y232169D01*
X73865Y231919D01*
X74240Y231836D01*
Y233586D01*
G01X73948Y235103D02*
X74157Y235394D01*
X74240Y235728D01*
X74157Y236061D01*
X73907Y236353D01*
X73532Y236561D01*
X73157Y236644D01*
X72698D01*
X72323Y236561D01*
X71990Y236353D01*
X71823Y236103D01*
X71740Y235811D01*
X71823Y235478D01*
X71990Y235228D01*
X72240Y235061D01*
X72573Y234978D01*
X72865Y235061D01*
X73157Y235269D01*
X73323Y235519D01*
X73365Y235811D01*
X73282Y236144D01*
X73073Y236394D01*
X72698Y236644D01*
G01X62178Y230657D02*
X62053Y230407D01*
X61970Y230115D01*
Y229782D01*
X62095Y229407D01*
X62303Y229115D01*
X62553Y228907D01*
X62970Y228740D01*
X63345Y228698D01*
X63720Y228782D01*
X63970Y228907D01*
X64220Y229157D01*
X64387Y229448D01*
X64470Y229740D01*
Y230032D01*
X64387Y230323D01*
X64262Y230573D01*
X64095Y230782D01*
G01X63970Y231923D02*
X64262Y232173D01*
X64428Y232507D01*
X64470Y232882D01*
X64428Y233215D01*
X64220Y233548D01*
X63970Y233757D01*
X63720Y233798D01*
X63428Y233715D01*
X63220Y233423D01*
X63137Y233132D01*
Y232757D01*
G01Y233132D02*
X63012Y233382D01*
X62803Y233590D01*
X62553Y233673D01*
X62303Y233590D01*
X62095Y233382D01*
X61970Y233007D01*
X62012Y232632D01*
X62178Y232257D01*
G01X61970Y235940D02*
X62053Y235607D01*
X62262Y235357D01*
X62512Y235190D01*
X62845Y235065D01*
X63220Y235023D01*
X63595Y235065D01*
X63928Y235190D01*
X64178Y235357D01*
X64387Y235607D01*
X64470Y235940D01*
X64387Y236273D01*
X64178Y236523D01*
X63928Y236690D01*
X63595Y236815D01*
X63220Y236857D01*
X62845Y236815D01*
X62512Y236690D01*
X62262Y236523D01*
X62053Y236273D01*
X61970Y235940D01*
G01X101717Y218692D02*
X101467Y218817D01*
X101175Y218900D01*
X100842D01*
X100467Y218775D01*
X100175Y218567D01*
X99967Y218317D01*
X99800Y217900D01*
X99758Y217525D01*
X99842Y217150D01*
X99967Y216900D01*
X100217Y216650D01*
X100508Y216483D01*
X100800Y216400D01*
X101092D01*
X101383Y216483D01*
X101633Y216608D01*
X101842Y216775D01*
G01X102983Y216900D02*
X103233Y216608D01*
X103567Y216442D01*
X103942Y216400D01*
X104275Y216442D01*
X104608Y216650D01*
X104817Y216900D01*
X104858Y217150D01*
X104775Y217442D01*
X104483Y217650D01*
X104192Y217733D01*
X103817D01*
G01X104192D02*
X104442Y217858D01*
X104650Y218067D01*
X104733Y218317D01*
X104650Y218567D01*
X104442Y218775D01*
X104067Y218900D01*
X103692Y218858D01*
X103317Y218692D01*
G01X106208Y218483D02*
X106458Y218733D01*
X106750Y218858D01*
X107083Y218900D01*
X107500Y218817D01*
X107792Y218608D01*
X107875Y218358D01*
X107833Y218108D01*
X107667Y217900D01*
X106833Y217483D01*
X106458Y217192D01*
X106208Y216775D01*
X106125Y216400D01*
X107875D01*
G01X96184Y191597D02*
X95934Y191722D01*
X95642Y191805D01*
X95309D01*
X94934Y191680D01*
X94642Y191472D01*
X94434Y191222D01*
X94267Y190805D01*
X94225Y190430D01*
X94309Y190055D01*
X94434Y189805D01*
X94684Y189555D01*
X94975Y189388D01*
X95267Y189305D01*
X95559D01*
X95850Y189388D01*
X96100Y189513D01*
X96309Y189680D01*
G01X97575Y191388D02*
X97825Y191638D01*
X98117Y191763D01*
X98450Y191805D01*
X98867Y191722D01*
X99159Y191513D01*
X99242Y191263D01*
X99200Y191013D01*
X99034Y190805D01*
X98200Y190388D01*
X97825Y190097D01*
X97575Y189680D01*
X97492Y189305D01*
X99242D01*
G01X101967D02*
Y191805D01*
X100425Y190013D01*
X102509D01*
G01X101790Y214739D02*
X101540Y214864D01*
X101248Y214947D01*
X100915D01*
X100540Y214822D01*
X100248Y214614D01*
X100040Y214364D01*
X99873Y213947D01*
X99831Y213572D01*
X99915Y213197D01*
X100040Y212947D01*
X100290Y212697D01*
X100581Y212530D01*
X100873Y212447D01*
X101165D01*
X101456Y212530D01*
X101706Y212655D01*
X101915Y212822D01*
G01X103181Y214530D02*
X103431Y214780D01*
X103723Y214905D01*
X104056Y214947D01*
X104473Y214864D01*
X104765Y214655D01*
X104848Y214405D01*
X104806Y214155D01*
X104640Y213947D01*
X103806Y213530D01*
X103431Y213239D01*
X103181Y212822D01*
X103098Y212447D01*
X104848D01*
G01X106156Y212947D02*
X106406Y212655D01*
X106740Y212489D01*
X107115Y212447D01*
X107448Y212489D01*
X107781Y212697D01*
X107990Y212947D01*
X108031Y213197D01*
X107948Y213489D01*
X107656Y213697D01*
X107365Y213780D01*
X106990D01*
G01X107365D02*
X107615Y213905D01*
X107823Y214114D01*
X107906Y214364D01*
X107823Y214614D01*
X107615Y214822D01*
X107240Y214947D01*
X106865Y214905D01*
X106490Y214739D01*
G01X95817Y187292D02*
X95567Y187417D01*
X95275Y187500D01*
X94942D01*
X94567Y187375D01*
X94275Y187167D01*
X94067Y186917D01*
X93900Y186500D01*
X93858Y186125D01*
X93942Y185750D01*
X94067Y185500D01*
X94317Y185250D01*
X94608Y185083D01*
X94900Y185000D01*
X95192D01*
X95483Y185083D01*
X95733Y185208D01*
X95942Y185375D01*
G01X97208Y187083D02*
X97458Y187333D01*
X97750Y187458D01*
X98083Y187500D01*
X98500Y187417D01*
X98792Y187208D01*
X98875Y186958D01*
X98833Y186708D01*
X98667Y186500D01*
X97833Y186083D01*
X97458Y185792D01*
X97208Y185375D01*
X97125Y185000D01*
X98875D01*
G01X100308Y187083D02*
X100558Y187333D01*
X100850Y187458D01*
X101183Y187500D01*
X101600Y187417D01*
X101892Y187208D01*
X101975Y186958D01*
X101933Y186708D01*
X101767Y186500D01*
X100933Y186083D01*
X100558Y185792D01*
X100308Y185375D01*
X100225Y185000D01*
X101975D01*
G01X37508Y217017D02*
X37383Y216767D01*
X37300Y216475D01*
Y216142D01*
X37425Y215767D01*
X37633Y215475D01*
X37883Y215267D01*
X38300Y215100D01*
X38675Y215058D01*
X39050Y215142D01*
X39300Y215267D01*
X39550Y215517D01*
X39717Y215808D01*
X39800Y216100D01*
Y216392D01*
X39717Y216683D01*
X39592Y216933D01*
X39425Y217142D01*
G01Y218283D02*
X39633Y218533D01*
X39758Y218825D01*
X39800Y219200D01*
X39717Y219575D01*
X39550Y219867D01*
X39258Y220075D01*
X38925Y220117D01*
X38592Y220033D01*
X38383Y219825D01*
X38217Y219533D01*
X38175Y219242D01*
X38217Y218950D01*
X38383Y218575D01*
X37300Y218700D01*
Y219825D01*
G01X39800Y222217D02*
X39258Y222300D01*
X38800Y222425D01*
X38383Y222592D01*
X37925Y222800D01*
X37300Y223133D01*
Y221467D01*
G01X107000Y231567D02*
X104500D01*
Y232608D01*
X104625Y232942D01*
X104792Y233150D01*
X105125Y233233D01*
X105458Y233150D01*
X105667Y232900D01*
X105792Y232608D01*
Y231567D01*
G01Y232608D02*
X107000Y233233D01*
G01X105958Y234708D02*
X105667Y235000D01*
X105500Y235250D01*
X105417Y235583D01*
X105500Y235875D01*
X105667Y236083D01*
X105917Y236250D01*
X106208Y236292D01*
X106458Y236250D01*
X106708Y236083D01*
X106917Y235833D01*
X107000Y235542D01*
X106917Y235208D01*
X106667Y234917D01*
X106292Y234750D01*
X105875Y234708D01*
X105333Y234792D01*
X105042Y234917D01*
X104750Y235125D01*
X104542Y235417D01*
X104500Y235708D01*
X104583Y236000D01*
X104792Y236208D01*
G01X107000Y238600D02*
X104500D01*
X105000Y238100D01*
G01X107000D02*
Y239100D01*
G01X104178Y221217D02*
X108178D01*
Y228617D01*
G01X43800Y215267D02*
X41300D01*
Y216308D01*
X41425Y216642D01*
X41592Y216850D01*
X41925Y216933D01*
X42258Y216850D01*
X42467Y216600D01*
X42592Y216308D01*
Y215267D01*
G01Y216308D02*
X43800Y216933D01*
G01Y219700D02*
X41300D01*
X43092Y218158D01*
Y220242D01*
G01X43508Y221592D02*
X43717Y221883D01*
X43800Y222217D01*
X43717Y222550D01*
X43467Y222842D01*
X43092Y223050D01*
X42717Y223133D01*
X42258D01*
X41883Y223050D01*
X41550Y222842D01*
X41383Y222592D01*
X41300Y222300D01*
X41383Y221967D01*
X41550Y221717D01*
X41800Y221550D01*
X42133Y221467D01*
X42425Y221550D01*
X42717Y221758D01*
X42883Y222008D01*
X42925Y222300D01*
X42842Y222633D01*
X42633Y222883D01*
X42258Y223133D01*
G01X61400Y205000D02*
X65400D01*
Y212400D01*
G01X47800Y215267D02*
X45300D01*
Y216308D01*
X45425Y216642D01*
X45592Y216850D01*
X45925Y216933D01*
X46258Y216850D01*
X46467Y216600D01*
X46592Y216308D01*
Y215267D01*
G01Y216308D02*
X47800Y216933D01*
G01Y219700D02*
X45300D01*
X47092Y218158D01*
Y220242D01*
G01X47800Y222300D02*
X47758Y222592D01*
X47633Y222925D01*
X47425Y223133D01*
X47133Y223217D01*
X46842Y223133D01*
X46592Y222883D01*
X46467Y222508D01*
Y222092D01*
X46383Y221842D01*
X46175Y221633D01*
X45883Y221550D01*
X45592Y221675D01*
X45383Y221967D01*
X45300Y222300D01*
X45383Y222633D01*
X45592Y222925D01*
X45883Y223050D01*
X46175Y222967D01*
X46383Y222758D01*
X46467Y222508D01*
Y222092D01*
X46592Y221717D01*
X46842Y221467D01*
X47133Y221383D01*
X47425Y221467D01*
X47633Y221675D01*
X47758Y222008D01*
X47800Y222300D01*
G01X65400Y205000D02*
X69400D01*
Y212400D01*
G01X51800Y215267D02*
X49300D01*
Y216308D01*
X49425Y216642D01*
X49592Y216850D01*
X49925Y216933D01*
X50258Y216850D01*
X50467Y216600D01*
X50592Y216308D01*
Y215267D01*
G01Y216308D02*
X51800Y216933D01*
G01X51508Y218492D02*
X51717Y218783D01*
X51800Y219117D01*
X51717Y219450D01*
X51467Y219742D01*
X51092Y219950D01*
X50717Y220033D01*
X50258D01*
X49883Y219950D01*
X49550Y219742D01*
X49383Y219492D01*
X49300Y219200D01*
X49383Y218867D01*
X49550Y218617D01*
X49800Y218450D01*
X50133Y218367D01*
X50425Y218450D01*
X50717Y218658D01*
X50883Y218908D01*
X50925Y219200D01*
X50842Y219533D01*
X50633Y219783D01*
X50258Y220033D01*
G01X69500Y205000D02*
X73500D01*
Y212400D01*
G01X63800Y215267D02*
X61300D01*
Y216308D01*
X61425Y216642D01*
X61592Y216850D01*
X61925Y216933D01*
X62258Y216850D01*
X62467Y216600D01*
X62592Y216308D01*
Y215267D01*
G01Y216308D02*
X63800Y216933D01*
G01X63425Y218283D02*
X63633Y218533D01*
X63758Y218825D01*
X63800Y219200D01*
X63717Y219575D01*
X63550Y219867D01*
X63258Y220075D01*
X62925Y220117D01*
X62592Y220033D01*
X62383Y219825D01*
X62217Y219533D01*
X62175Y219242D01*
X62217Y218950D01*
X62383Y218575D01*
X61300Y218700D01*
Y219825D01*
G01X63508Y221592D02*
X63717Y221883D01*
X63800Y222217D01*
X63717Y222550D01*
X63467Y222842D01*
X63092Y223050D01*
X62717Y223133D01*
X62258D01*
X61883Y223050D01*
X61550Y222842D01*
X61383Y222592D01*
X61300Y222300D01*
X61383Y221967D01*
X61550Y221717D01*
X61800Y221550D01*
X62133Y221467D01*
X62425Y221550D01*
X62717Y221758D01*
X62883Y222008D01*
X62925Y222300D01*
X62842Y222633D01*
X62633Y222883D01*
X62258Y223133D01*
G01X81500Y205000D02*
X85500D01*
Y212400D01*
G01X81100Y215267D02*
X78600D01*
Y216308D01*
X78725Y216642D01*
X78892Y216850D01*
X79225Y216933D01*
X79558Y216850D01*
X79767Y216600D01*
X79892Y216308D01*
Y215267D01*
G01Y216308D02*
X81100Y216933D01*
G01X80725Y218283D02*
X80933Y218533D01*
X81058Y218825D01*
X81100Y219200D01*
X81017Y219575D01*
X80850Y219867D01*
X80558Y220075D01*
X80225Y220117D01*
X79892Y220033D01*
X79683Y219825D01*
X79517Y219533D01*
X79475Y219242D01*
X79517Y218950D01*
X79683Y218575D01*
X78600Y218700D01*
Y219825D01*
G01X81100Y222300D02*
X81058Y222592D01*
X80933Y222925D01*
X80725Y223133D01*
X80433Y223217D01*
X80142Y223133D01*
X79892Y222883D01*
X79767Y222508D01*
Y222092D01*
X79683Y221842D01*
X79475Y221633D01*
X79183Y221550D01*
X78892Y221675D01*
X78683Y221967D01*
X78600Y222300D01*
X78683Y222633D01*
X78892Y222925D01*
X79183Y223050D01*
X79475Y222967D01*
X79683Y222758D01*
X79767Y222508D01*
Y222092D01*
X79892Y221717D01*
X80142Y221467D01*
X80433Y221383D01*
X80725Y221467D01*
X80933Y221675D01*
X81058Y222008D01*
X81100Y222300D01*
G01X93900Y205000D02*
X97900D01*
Y212400D01*
G01X35800Y215267D02*
X33300D01*
Y216308D01*
X33425Y216642D01*
X33592Y216850D01*
X33925Y216933D01*
X34258Y216850D01*
X34467Y216600D01*
X34592Y216308D01*
Y215267D01*
G01Y216308D02*
X35800Y216933D01*
G01Y219200D02*
X33300D01*
X33800Y218700D01*
G01X35800D02*
Y219700D01*
G01X33717Y221508D02*
X33467Y221758D01*
X33342Y222050D01*
X33300Y222383D01*
X33383Y222800D01*
X33592Y223092D01*
X33842Y223175D01*
X34092Y223133D01*
X34300Y222967D01*
X34717Y222133D01*
X35008Y221758D01*
X35425Y221508D01*
X35800Y221425D01*
Y223175D01*
G01X53900Y205000D02*
X57900D01*
Y212400D01*
G01X55800Y215267D02*
X53300D01*
Y216308D01*
X53425Y216642D01*
X53592Y216850D01*
X53925Y216933D01*
X54258Y216850D01*
X54467Y216600D01*
X54592Y216308D01*
Y215267D01*
G01Y216308D02*
X55800Y216933D01*
G01Y219200D02*
X55758Y219492D01*
X55633Y219825D01*
X55425Y220033D01*
X55133Y220117D01*
X54842Y220033D01*
X54592Y219783D01*
X54467Y219408D01*
Y218992D01*
X54383Y218742D01*
X54175Y218533D01*
X53883Y218450D01*
X53592Y218575D01*
X53383Y218867D01*
X53300Y219200D01*
X53383Y219533D01*
X53592Y219825D01*
X53883Y219950D01*
X54175Y219867D01*
X54383Y219658D01*
X54467Y219408D01*
Y218992D01*
X54592Y218617D01*
X54842Y218367D01*
X55133Y218283D01*
X55425Y218367D01*
X55633Y218575D01*
X55758Y218908D01*
X55800Y219200D01*
G01X77500Y212400D02*
X73500D01*
Y205000D01*
G01X59800Y215267D02*
X57300D01*
Y216308D01*
X57425Y216642D01*
X57592Y216850D01*
X57925Y216933D01*
X58258Y216850D01*
X58467Y216600D01*
X58592Y216308D01*
Y215267D01*
G01Y216308D02*
X59800Y216933D01*
G01Y219117D02*
X59258Y219200D01*
X58800Y219325D01*
X58383Y219492D01*
X57925Y219700D01*
X57300Y220033D01*
Y218367D01*
G01X81500Y212400D02*
X77500D01*
Y205000D01*
G01X71800Y215267D02*
X69300D01*
Y216308D01*
X69425Y216642D01*
X69592Y216850D01*
X69925Y216933D01*
X70258Y216850D01*
X70467Y216600D01*
X70592Y216308D01*
Y215267D01*
G01Y216308D02*
X71800Y216933D01*
G01Y219200D02*
X69300D01*
X69800Y218700D01*
G01X71800D02*
Y219700D01*
G01X69300Y222300D02*
X69383Y221967D01*
X69592Y221717D01*
X69842Y221550D01*
X70175Y221425D01*
X70550Y221383D01*
X70925Y221425D01*
X71258Y221550D01*
X71508Y221717D01*
X71717Y221967D01*
X71800Y222300D01*
X71717Y222633D01*
X71508Y222883D01*
X71258Y223050D01*
X70925Y223175D01*
X70550Y223217D01*
X70175Y223175D01*
X69842Y223050D01*
X69592Y222883D01*
X69383Y222633D01*
X69300Y222300D01*
G01X93700Y212400D02*
X89700D01*
Y205000D01*
G01X67800Y215267D02*
X65300D01*
Y216308D01*
X65425Y216642D01*
X65592Y216850D01*
X65925Y216933D01*
X66258Y216850D01*
X66467Y216600D01*
X66592Y216308D01*
Y215267D01*
G01Y216308D02*
X67800Y216933D01*
G01Y219200D02*
X65300D01*
X65800Y218700D01*
G01X67800D02*
Y219700D01*
G01Y222300D02*
X65300D01*
X65800Y221800D01*
G01X67800D02*
Y222800D01*
G01X89500Y212400D02*
X85500D01*
Y205000D01*
G01X52550Y185900D02*
X48550Y181900D01*
G01X52550Y205900D02*
Y185900D01*
G01X48550Y209900D02*
X52550Y205900D01*
G01X171400Y7000D02*
Y17000D01*
X169400Y15000D01*
G01Y7000D02*
X173400D01*
G01X178333Y8500D02*
X179333Y7667D01*
X180500Y7167D01*
X182000Y7000D01*
X183500Y7333D01*
X184667Y8000D01*
X185500Y9167D01*
X185667Y10500D01*
X185333Y11833D01*
X184500Y12667D01*
X183333Y13333D01*
X182167Y13500D01*
X181000Y13333D01*
X179500Y12667D01*
X180000Y17000D01*
X184500D01*
G01X189767Y8166D02*
X190933Y7333D01*
X192267Y7000D01*
X193600Y7333D01*
X194767Y8333D01*
X195600Y9833D01*
X195933Y11333D01*
Y13167D01*
X195600Y14667D01*
X194767Y16000D01*
X193767Y16667D01*
X192600Y17000D01*
X191266Y16667D01*
X190267Y16000D01*
X189600Y15000D01*
X189267Y13666D01*
X189600Y12500D01*
X190433Y11333D01*
X191433Y10666D01*
X192600Y10500D01*
X193933Y10833D01*
X194933Y11667D01*
X195933Y13167D01*
G01X200033Y11166D02*
X201200Y12333D01*
X202200Y13000D01*
X203533Y13333D01*
X204700Y13000D01*
X205533Y12333D01*
X206200Y11333D01*
X206367Y10167D01*
X206200Y9167D01*
X205533Y8166D01*
X204533Y7333D01*
X203367Y7000D01*
X202033Y7333D01*
X200867Y8333D01*
X200200Y9833D01*
X200033Y11500D01*
X200367Y13666D01*
X200867Y14833D01*
X201700Y16000D01*
X202867Y16833D01*
X204033Y17000D01*
X205200Y16667D01*
X206033Y15833D01*
G01X213800Y7000D02*
X214967Y7167D01*
X216300Y7667D01*
X217133Y8500D01*
X217467Y9667D01*
X217133Y10833D01*
X216133Y11833D01*
X214633Y12333D01*
X212967D01*
X211967Y12667D01*
X211133Y13500D01*
X210800Y14667D01*
X211300Y15833D01*
X212466Y16667D01*
X213800Y17000D01*
X215133Y16667D01*
X216300Y15833D01*
X216800Y14667D01*
X216467Y13500D01*
X215633Y12667D01*
X214633Y12333D01*
X212967D01*
X211467Y11833D01*
X210467Y10833D01*
X210133Y9667D01*
X210467Y8500D01*
X211300Y7667D01*
X212633Y7167D01*
X213800Y7000D01*
G01X222233Y10333D02*
X226567D01*
G01X235000Y7000D02*
Y17000D01*
X233000Y15000D01*
G01Y7000D02*
X237000D01*
G01X241433D02*
X245600Y17000D01*
X249767Y7000D01*
G01X248267Y10500D02*
X242933D01*
G01X146067Y-39600D02*
Y-29600D01*
X150400Y-37933D01*
X154733Y-29600D01*
Y-39600D01*
G01X156833D02*
X161000Y-29600D01*
X165167Y-39600D01*
G01X163667Y-36100D02*
X158333D01*
G01X167933Y-39600D02*
Y-29600D01*
X171267D01*
X172600Y-30100D01*
X173600Y-30767D01*
X174433Y-31767D01*
X175100Y-32934D01*
X175267Y-34600D01*
X175100Y-36267D01*
X174433Y-37433D01*
X173600Y-38434D01*
X172600Y-39100D01*
X171267Y-39600D01*
X167933D01*
G01X185533D02*
X178867D01*
Y-29600D01*
X185533D01*
G01X182867Y-34433D02*
X178867D01*
G01X201400Y-29600D02*
X205400D01*
G01X203400D02*
Y-39600D01*
G01X201400D02*
X205400D01*
G01X210167D02*
Y-29600D01*
X217833Y-39600D01*
Y-29600D01*
G01X235200D02*
Y-39600D01*
G01X231367Y-29600D02*
X239033D01*
G01X241633Y-39600D02*
X245800Y-29600D01*
X249967Y-39600D01*
G01X248467Y-36100D02*
X243133D01*
G01X254400Y-29600D02*
X258400D01*
G01X256400D02*
Y-39600D01*
G01X254400D02*
X258400D01*
G01X262000Y-29600D02*
X264333Y-39600D01*
X267000Y-29600D01*
X269667Y-39600D01*
X272000Y-29600D01*
G01X273433Y-39600D02*
X277600Y-29600D01*
X281767Y-39600D01*
G01X280267Y-36100D02*
X274933D01*
G01X284367Y-39600D02*
Y-29600D01*
X292033Y-39600D01*
Y-29600D01*
G01X175233Y-3267D02*
X175900Y-2767D01*
X176400Y-1934D01*
X176733Y-767D01*
X176400Y233D01*
X175733Y900D01*
X174567Y1400D01*
X170067D01*
Y-8600D01*
X175567D01*
X176733Y-7933D01*
X177400Y-6933D01*
X177733Y-5767D01*
X177400Y-4600D01*
X176400Y-3600D01*
X175233Y-3267D01*
X170067D01*
G01X186500Y-8600D02*
Y1400D01*
X180333Y-5767D01*
X188667D01*
G01X195100Y-8600D02*
X196267Y-8433D01*
X197600Y-7933D01*
X198433Y-7100D01*
X198767Y-5933D01*
X198433Y-4767D01*
X197433Y-3767D01*
X195933Y-3267D01*
X194267D01*
X193267Y-2933D01*
X192433Y-2100D01*
X192100Y-933D01*
X192600Y233D01*
X193766Y1067D01*
X195100Y1400D01*
X196433Y1067D01*
X197600Y233D01*
X198100Y-933D01*
X197767Y-2100D01*
X196933Y-2933D01*
X195933Y-3267D01*
X194267D01*
X192767Y-3767D01*
X191767Y-4767D01*
X191433Y-5933D01*
X191767Y-7100D01*
X192600Y-7933D01*
X193933Y-8433D01*
X195100Y-8600D01*
G01X205700Y-8933D02*
X205367Y-8767D01*
Y-8433D01*
X205700Y-8267D01*
X206033Y-8433D01*
Y-8767D01*
X205700Y-8933D01*
G01X216300Y1400D02*
X214966Y1067D01*
X213967Y233D01*
X213300Y-767D01*
X212800Y-2100D01*
X212633Y-3600D01*
X212800Y-5100D01*
X213300Y-6433D01*
X213967Y-7434D01*
X214966Y-8267D01*
X216300Y-8600D01*
X217633Y-8267D01*
X218633Y-7434D01*
X219300Y-6433D01*
X219800Y-5100D01*
X219967Y-3600D01*
X219800Y-2100D01*
X219300Y-767D01*
X218633Y233D01*
X217633Y1067D01*
X216300Y1400D01*
G01X226900D02*
X225566Y1067D01*
X224567Y233D01*
X223900Y-767D01*
X223400Y-2100D01*
X223233Y-3600D01*
X223400Y-5100D01*
X223900Y-6433D01*
X224567Y-7434D01*
X225566Y-8267D01*
X226900Y-8600D01*
X228233Y-8267D01*
X229233Y-7434D01*
X229900Y-6433D01*
X230400Y-5100D01*
X230567Y-3600D01*
X230400Y-2100D01*
X229900Y-767D01*
X229233Y233D01*
X228233Y1067D01*
X226900Y1400D01*
G01X234000Y-8600D02*
X241000Y1400D01*
G01X234000D02*
X241000Y-8600D01*
G01X248100Y1400D02*
X246766Y1067D01*
X245767Y233D01*
X245100Y-767D01*
X244600Y-2100D01*
X244433Y-3600D01*
X244600Y-5100D01*
X245100Y-6433D01*
X245767Y-7434D01*
X246766Y-8267D01*
X248100Y-8600D01*
X249433Y-8267D01*
X250433Y-7434D01*
X251100Y-6433D01*
X251600Y-5100D01*
X251767Y-3600D01*
X251600Y-2100D01*
X251100Y-767D01*
X250433Y233D01*
X249433Y1067D01*
X248100Y1400D01*
G01X255867Y-7434D02*
X257033Y-8267D01*
X258367Y-8600D01*
X259700Y-8267D01*
X260867Y-7267D01*
X261700Y-5767D01*
X262033Y-4267D01*
Y-2433D01*
X261700Y-933D01*
X260867Y400D01*
X259867Y1067D01*
X258700Y1400D01*
X257366Y1067D01*
X256367Y400D01*
X255700Y-600D01*
X255367Y-1934D01*
X255700Y-3100D01*
X256533Y-4267D01*
X257533Y-4934D01*
X258700Y-5100D01*
X260033Y-4767D01*
X261033Y-3933D01*
X262033Y-2433D01*
G01X269300Y-8933D02*
X268967Y-8767D01*
Y-8433D01*
X269300Y-8267D01*
X269633Y-8433D01*
Y-8767D01*
X269300Y-8933D01*
G01X279900Y1400D02*
X278566Y1067D01*
X277567Y233D01*
X276900Y-767D01*
X276400Y-2100D01*
X276233Y-3600D01*
X276400Y-5100D01*
X276900Y-6433D01*
X277567Y-7434D01*
X278566Y-8267D01*
X279900Y-8600D01*
X281233Y-8267D01*
X282233Y-7434D01*
X282900Y-6433D01*
X283400Y-5100D01*
X283567Y-3600D01*
X283400Y-2100D01*
X282900Y-767D01*
X282233Y233D01*
X281233Y1067D01*
X279900Y1400D01*
G01X290500D02*
X289166Y1067D01*
X288167Y233D01*
X287500Y-767D01*
X287000Y-2100D01*
X286833Y-3600D01*
X287000Y-5100D01*
X287500Y-6433D01*
X288167Y-7434D01*
X289166Y-8267D01*
X290500Y-8600D01*
X291833Y-8267D01*
X292833Y-7434D01*
X293500Y-6433D01*
X294000Y-5100D01*
X294167Y-3600D01*
X294000Y-2100D01*
X293500Y-767D01*
X292833Y233D01*
X291833Y1067D01*
X290500Y1400D01*
G01X301100Y-8600D02*
Y1400D01*
X299100Y-600D01*
G01Y-8600D02*
X303100D01*
G01X307533D02*
X311700Y1400D01*
X315867Y-8600D01*
G01X314367Y-5100D02*
X309033D01*
G01X128233Y-23100D02*
Y-13100D01*
X131567D01*
X132900Y-13600D01*
X133900Y-14267D01*
X134733Y-15267D01*
X135400Y-16434D01*
X135567Y-18100D01*
X135400Y-19767D01*
X134733Y-20933D01*
X133900Y-21934D01*
X132900Y-22600D01*
X131567Y-23100D01*
X128233D01*
G01X138333Y-13100D02*
X142500Y-23100D01*
X146667Y-13100D01*
G01X153100D02*
Y-23100D01*
G01X149267Y-13100D02*
X156933D01*
G01X170967Y-23100D02*
Y-13100D01*
X175133D01*
X176467Y-13600D01*
X177300Y-14267D01*
X177633Y-15600D01*
X177300Y-16933D01*
X176300Y-17767D01*
X175133Y-18267D01*
X170967D01*
G01X175133D02*
X177633Y-23100D01*
G01X184900Y-16434D02*
Y-23100D01*
G01Y-13767D02*
X184567Y-13600D01*
Y-13267D01*
X184900Y-13100D01*
X185233Y-13267D01*
Y-13600D01*
X184900Y-13767D01*
G01X193000Y-21934D02*
X193833Y-22600D01*
X195000Y-23100D01*
X196000D01*
X197000Y-22767D01*
X197667Y-22267D01*
X198000Y-21600D01*
X197833Y-20600D01*
X197167Y-20100D01*
X194166Y-19100D01*
X193500Y-17933D01*
X193833Y-17100D01*
X194500Y-16600D01*
X195500Y-16434D01*
X196500Y-16600D01*
X197500Y-17100D01*
G01X203600Y-18600D02*
X208933D01*
X208433Y-17433D01*
X207600Y-16767D01*
X206433Y-16434D01*
X205267Y-16600D01*
X204267Y-17100D01*
X203600Y-18267D01*
X203267Y-19267D01*
Y-20267D01*
X203600Y-21267D01*
X204433Y-22267D01*
X205433Y-22933D01*
X206600Y-23100D01*
X207767Y-22767D01*
X208933Y-21767D01*
G01X214367Y-23100D02*
Y-16434D01*
G01Y-17767D02*
X215200Y-17100D01*
X216033Y-16600D01*
X217200Y-16434D01*
X218033Y-16600D01*
X219033Y-17100D01*
G01X241567Y-13933D02*
X240567Y-13433D01*
X239400Y-13100D01*
X238067D01*
X236566Y-13600D01*
X235400Y-14433D01*
X234567Y-15433D01*
X233900Y-17100D01*
X233733Y-18600D01*
X234067Y-20100D01*
X234567Y-21100D01*
X235567Y-22100D01*
X236733Y-22767D01*
X237900Y-23100D01*
X239067D01*
X240233Y-22767D01*
X241233Y-22267D01*
X242067Y-21600D01*
G01X251500Y-23100D02*
Y-16434D01*
G01Y-17600D02*
X250833Y-16933D01*
X249833Y-16600D01*
X248667Y-16434D01*
X247500Y-16767D01*
X246500Y-17433D01*
X245833Y-18433D01*
X245500Y-19767D01*
X245833Y-21100D01*
X246500Y-22100D01*
X247500Y-22767D01*
X248667Y-23100D01*
X249833Y-22933D01*
X250833Y-22433D01*
X251500Y-21767D01*
G01X256767Y-23100D02*
Y-16434D01*
G01Y-17767D02*
X257600Y-17100D01*
X258433Y-16600D01*
X259600Y-16434D01*
X260433Y-16600D01*
X261433Y-17100D01*
G01X272700Y-13100D02*
Y-23100D01*
G01Y-21600D02*
X272033Y-22433D01*
X271033Y-22933D01*
X269867Y-23100D01*
X268533Y-22767D01*
X267533Y-21934D01*
X266867Y-20933D01*
X266700Y-19767D01*
X266867Y-18600D01*
X267533Y-17600D01*
X268533Y-16767D01*
X269867Y-16434D01*
X271033Y-16600D01*
X271867Y-16933D01*
X272700Y-17600D01*
G01X275300Y-26433D02*
X285300D01*
G01X287400Y-21767D02*
X288733Y-22600D01*
X290233Y-23100D01*
X291567D01*
X292900Y-22600D01*
X293900Y-21767D01*
X294400Y-20600D01*
X294067Y-19434D01*
X293233Y-18433D01*
X291733Y-17767D01*
X289733Y-17433D01*
X288567Y-16767D01*
X288067Y-15600D01*
X288400Y-14433D01*
X289233Y-13600D01*
X290400Y-13100D01*
X291567D01*
X292733Y-13433D01*
X293733Y-14267D01*
G01X298000Y-21767D02*
X299333Y-22600D01*
X300833Y-23100D01*
X302167D01*
X303500Y-22600D01*
X304500Y-21767D01*
X305000Y-20600D01*
X304667Y-19434D01*
X303833Y-18433D01*
X302333Y-17767D01*
X300333Y-17433D01*
X299167Y-16767D01*
X298667Y-15600D01*
X299000Y-14433D01*
X299833Y-13600D01*
X301000Y-13100D01*
X302167D01*
X303333Y-13433D01*
X304333Y-14267D01*
G01X319533Y-14767D02*
X320533Y-13767D01*
X321700Y-13267D01*
X323033Y-13100D01*
X324700Y-13433D01*
X325867Y-14267D01*
X326200Y-15267D01*
X326033Y-16267D01*
X325367Y-17100D01*
X322033Y-18767D01*
X320533Y-19933D01*
X319533Y-21600D01*
X319200Y-23100D01*
X326200D01*
G01X341400Y-21934D02*
X342233Y-22600D01*
X343400Y-23100D01*
X344400D01*
X345400Y-22767D01*
X346067Y-22267D01*
X346400Y-21600D01*
X346233Y-20600D01*
X345567Y-20100D01*
X342566Y-19100D01*
X341900Y-17933D01*
X342233Y-17100D01*
X342900Y-16600D01*
X343900Y-16434D01*
X344900Y-16600D01*
X345900Y-17100D01*
G01X354500Y-23100D02*
Y-13100D01*
G01X365100Y-23100D02*
X364100Y-22933D01*
X363100Y-22267D01*
X362433Y-21100D01*
X362100Y-19767D01*
X362433Y-18433D01*
X363100Y-17267D01*
X364100Y-16600D01*
X365100Y-16434D01*
X366100Y-16600D01*
X367100Y-17267D01*
X367767Y-18433D01*
X367933Y-19767D01*
X367767Y-21100D01*
X367100Y-22267D01*
X366100Y-22933D01*
X365100Y-23100D01*
G01X375700Y-13100D02*
Y-23100D01*
G01X373367Y-16434D02*
X378033D01*
G01X383800Y-21934D02*
X384633Y-22600D01*
X385800Y-23100D01*
X386800D01*
X387800Y-22767D01*
X388467Y-22267D01*
X388800Y-21600D01*
X388633Y-20600D01*
X387967Y-20100D01*
X384966Y-19100D01*
X384300Y-17933D01*
X384633Y-17100D01*
X385300Y-16600D01*
X386300Y-16434D01*
X387300Y-16600D01*
X388300Y-17100D01*
G01X117200Y3017D02*
X114700D01*
Y4058D01*
X114825Y4392D01*
X114992Y4600D01*
X115325Y4683D01*
X115658Y4600D01*
X115867Y4350D01*
X115992Y4058D01*
Y3017D01*
G01Y4058D02*
X117200Y4683D01*
G01X115117Y6158D02*
X114867Y6408D01*
X114742Y6700D01*
X114700Y7033D01*
X114783Y7450D01*
X114992Y7742D01*
X115242Y7825D01*
X115492Y7783D01*
X115700Y7617D01*
X116117Y6783D01*
X116408Y6408D01*
X116825Y6158D01*
X117200Y6075D01*
Y7825D01*
G01X118000Y19900D02*
X114000D01*
Y12500D01*
G01X113000Y2967D02*
X110500D01*
Y4008D01*
X110625Y4342D01*
X110792Y4550D01*
X111125Y4633D01*
X111458Y4550D01*
X111667Y4300D01*
X111792Y4008D01*
Y2967D01*
G01Y4008D02*
X113000Y4633D01*
G01X112625Y5983D02*
X112833Y6233D01*
X112958Y6525D01*
X113000Y6900D01*
X112917Y7275D01*
X112750Y7567D01*
X112458Y7775D01*
X112125Y7817D01*
X111792Y7733D01*
X111583Y7525D01*
X111417Y7233D01*
X111375Y6942D01*
X111417Y6650D01*
X111583Y6275D01*
X110500Y6400D01*
Y7525D01*
G01X113000Y9917D02*
X112458Y10000D01*
X112000Y10125D01*
X111583Y10292D01*
X111125Y10500D01*
X110500Y10833D01*
Y9167D01*
G01X113800Y19900D02*
X109800D01*
Y12500D01*
G01X162030Y14019D02*
X159530D01*
Y15060D01*
X159655Y15394D01*
X159822Y15602D01*
X160155Y15685D01*
X160488Y15602D01*
X160697Y15352D01*
X160822Y15060D01*
Y14019D01*
G01Y15060D02*
X162030Y15685D01*
G01Y17952D02*
X159530D01*
X160030Y17452D01*
G01X162030D02*
Y18452D01*
G01X160988Y20260D02*
X160697Y20552D01*
X160530Y20802D01*
X160447Y21135D01*
X160530Y21427D01*
X160697Y21635D01*
X160947Y21802D01*
X161238Y21844D01*
X161488Y21802D01*
X161738Y21635D01*
X161947Y21385D01*
X162030Y21094D01*
X161947Y20760D01*
X161697Y20469D01*
X161322Y20302D01*
X160905Y20260D01*
X160363Y20344D01*
X160072Y20469D01*
X159780Y20677D01*
X159572Y20969D01*
X159530Y21260D01*
X159613Y21552D01*
X159822Y21760D01*
G01X162030Y24069D02*
X161488Y24152D01*
X161030Y24277D01*
X160613Y24444D01*
X160155Y24652D01*
X159530Y24985D01*
Y23319D01*
G01X158300Y20600D02*
X154300D01*
Y13200D01*
G01X143100Y1450D02*
X143058Y1117D01*
X142892Y825D01*
X142642Y575D01*
X142350Y408D01*
X142017Y325D01*
X141683D01*
X141350Y408D01*
X141058Y575D01*
X140808Y825D01*
X140642Y1117D01*
X140600Y1450D01*
X140642Y1783D01*
X140808Y2075D01*
X141058Y2325D01*
X141350Y2492D01*
X141683Y2575D01*
X142017D01*
X142350Y2492D01*
X142642Y2325D01*
X142892Y2075D01*
X143058Y1783D01*
X143100Y1450D01*
G01X142433Y1783D02*
X143100Y2283D01*
G01Y4550D02*
X140600D01*
X141100Y4050D01*
G01X143100D02*
Y5050D01*
G01X147448Y-3042D02*
X158848D01*
G01X147448Y10358D02*
Y-3042D01*
G01X158848Y10358D02*
X147448D01*
G01X158848Y-3042D02*
Y10358D01*
G01X164908Y82617D02*
X164783Y82367D01*
X164700Y82075D01*
Y81742D01*
X164825Y81367D01*
X165033Y81075D01*
X165283Y80867D01*
X165700Y80700D01*
X166075Y80658D01*
X166450Y80742D01*
X166700Y80867D01*
X166950Y81117D01*
X167117Y81408D01*
X167200Y81700D01*
Y81992D01*
X167117Y82283D01*
X166992Y82533D01*
X166825Y82742D01*
G01X166700Y83883D02*
X166992Y84133D01*
X167158Y84467D01*
X167200Y84842D01*
X167158Y85175D01*
X166950Y85508D01*
X166700Y85717D01*
X166450Y85758D01*
X166158Y85675D01*
X165950Y85383D01*
X165867Y85092D01*
Y84717D01*
G01Y85092D02*
X165742Y85342D01*
X165533Y85550D01*
X165283Y85633D01*
X165033Y85550D01*
X164825Y85342D01*
X164700Y84967D01*
X164742Y84592D01*
X164908Y84217D01*
G01X166158Y87108D02*
X165867Y87400D01*
X165700Y87650D01*
X165617Y87983D01*
X165700Y88275D01*
X165867Y88483D01*
X166117Y88650D01*
X166408Y88692D01*
X166658Y88650D01*
X166908Y88483D01*
X167117Y88233D01*
X167200Y87942D01*
X167117Y87608D01*
X166867Y87317D01*
X166492Y87150D01*
X166075Y87108D01*
X165533Y87192D01*
X165242Y87317D01*
X164950Y87525D01*
X164742Y87817D01*
X164700Y88108D01*
X164783Y88400D01*
X164992Y88608D01*
G01X174608Y97317D02*
X174483Y97067D01*
X174400Y96775D01*
Y96442D01*
X174525Y96067D01*
X174733Y95775D01*
X174983Y95567D01*
X175400Y95400D01*
X175775Y95358D01*
X176150Y95442D01*
X176400Y95567D01*
X176650Y95817D01*
X176817Y96108D01*
X176900Y96400D01*
Y96692D01*
X176817Y96983D01*
X176692Y97233D01*
X176525Y97442D01*
G01X176900Y100000D02*
X174400D01*
X176192Y98458D01*
Y100542D01*
G01X176900Y102600D02*
X176858Y102892D01*
X176733Y103225D01*
X176525Y103433D01*
X176233Y103517D01*
X175942Y103433D01*
X175692Y103183D01*
X175567Y102808D01*
Y102392D01*
X175483Y102142D01*
X175275Y101933D01*
X174983Y101850D01*
X174692Y101975D01*
X174483Y102267D01*
X174400Y102600D01*
X174483Y102933D01*
X174692Y103225D01*
X174983Y103350D01*
X175275Y103267D01*
X175483Y103058D01*
X175567Y102808D01*
Y102392D01*
X175692Y102017D01*
X175942Y101767D01*
X176233Y101683D01*
X176525Y101767D01*
X176733Y101975D01*
X176858Y102308D01*
X176900Y102600D01*
G01X165517Y58592D02*
X165267Y58717D01*
X164975Y58800D01*
X164642D01*
X164267Y58675D01*
X163975Y58467D01*
X163767Y58217D01*
X163600Y57800D01*
X163558Y57425D01*
X163642Y57050D01*
X163767Y56800D01*
X164017Y56550D01*
X164308Y56383D01*
X164600Y56300D01*
X164892D01*
X165183Y56383D01*
X165433Y56508D01*
X165642Y56675D01*
G01X166783Y56800D02*
X167033Y56508D01*
X167367Y56342D01*
X167742Y56300D01*
X168075Y56342D01*
X168408Y56550D01*
X168617Y56800D01*
X168658Y57050D01*
X168575Y57342D01*
X168283Y57550D01*
X167992Y57633D01*
X167617D01*
G01X167992D02*
X168242Y57758D01*
X168450Y57967D01*
X168533Y58217D01*
X168450Y58467D01*
X168242Y58675D01*
X167867Y58800D01*
X167492Y58758D01*
X167117Y58592D01*
G01X170717Y56300D02*
X170800Y56842D01*
X170925Y57300D01*
X171092Y57717D01*
X171300Y58175D01*
X171633Y58800D01*
X169967D01*
G01X132403Y86808D02*
X132153Y86933D01*
X131861Y87016D01*
X131528D01*
X131153Y86891D01*
X130861Y86683D01*
X130653Y86433D01*
X130486Y86016D01*
X130444Y85641D01*
X130528Y85266D01*
X130653Y85016D01*
X130903Y84766D01*
X131194Y84599D01*
X131486Y84516D01*
X131778D01*
X132069Y84599D01*
X132319Y84724D01*
X132528Y84891D01*
G01X134586Y84516D02*
Y87016D01*
X134086Y86516D01*
G01Y84516D02*
X135086D01*
G01X136978Y84808D02*
X137269Y84599D01*
X137603Y84516D01*
X137936Y84599D01*
X138228Y84849D01*
X138436Y85224D01*
X138519Y85599D01*
Y86058D01*
X138436Y86433D01*
X138228Y86766D01*
X137978Y86933D01*
X137686Y87016D01*
X137353Y86933D01*
X137103Y86766D01*
X136936Y86516D01*
X136853Y86183D01*
X136936Y85891D01*
X137144Y85599D01*
X137394Y85433D01*
X137686Y85391D01*
X138019Y85474D01*
X138269Y85683D01*
X138519Y86058D01*
G01X133217Y82492D02*
X132967Y82617D01*
X132675Y82700D01*
X132342D01*
X131967Y82575D01*
X131675Y82367D01*
X131467Y82117D01*
X131300Y81700D01*
X131258Y81325D01*
X131342Y80950D01*
X131467Y80700D01*
X131717Y80450D01*
X132008Y80283D01*
X132300Y80200D01*
X132592D01*
X132883Y80283D01*
X133133Y80408D01*
X133342Y80575D01*
G01X135400Y80200D02*
Y82700D01*
X134900Y82200D01*
G01Y80200D02*
X135900D01*
G01X138500D02*
X138792Y80242D01*
X139125Y80367D01*
X139333Y80575D01*
X139417Y80867D01*
X139333Y81158D01*
X139083Y81408D01*
X138708Y81533D01*
X138292D01*
X138042Y81617D01*
X137833Y81825D01*
X137750Y82117D01*
X137875Y82408D01*
X138167Y82617D01*
X138500Y82700D01*
X138833Y82617D01*
X139125Y82408D01*
X139250Y82117D01*
X139167Y81825D01*
X138958Y81617D01*
X138708Y81533D01*
X138292D01*
X137917Y81408D01*
X137667Y81158D01*
X137583Y80867D01*
X137667Y80575D01*
X137875Y80367D01*
X138208Y80242D01*
X138500Y80200D01*
G01X133117Y78492D02*
X132867Y78617D01*
X132575Y78700D01*
X132242D01*
X131867Y78575D01*
X131575Y78367D01*
X131367Y78117D01*
X131200Y77700D01*
X131158Y77325D01*
X131242Y76950D01*
X131367Y76700D01*
X131617Y76450D01*
X131908Y76283D01*
X132200Y76200D01*
X132492D01*
X132783Y76283D01*
X133033Y76408D01*
X133242Y76575D01*
G01X135300Y76200D02*
Y78700D01*
X134800Y78200D01*
G01Y76200D02*
X135800D01*
G01X138317D02*
X138400Y76742D01*
X138525Y77200D01*
X138692Y77617D01*
X138900Y78075D01*
X139233Y78700D01*
X137567D01*
G01X140908Y48317D02*
X140783Y48067D01*
X140700Y47775D01*
Y47442D01*
X140825Y47067D01*
X141033Y46775D01*
X141283Y46567D01*
X141700Y46400D01*
X142075Y46358D01*
X142450Y46442D01*
X142700Y46567D01*
X142950Y46817D01*
X143117Y47108D01*
X143200Y47400D01*
Y47692D01*
X143117Y47983D01*
X142992Y48233D01*
X142825Y48442D01*
G01X142700Y49583D02*
X142992Y49833D01*
X143158Y50167D01*
X143200Y50542D01*
X143158Y50875D01*
X142950Y51208D01*
X142700Y51417D01*
X142450Y51458D01*
X142158Y51375D01*
X141950Y51083D01*
X141867Y50792D01*
Y50417D01*
G01Y50792D02*
X141742Y51042D01*
X141533Y51250D01*
X141283Y51333D01*
X141033Y51250D01*
X140825Y51042D01*
X140700Y50667D01*
X140742Y50292D01*
X140908Y49917D01*
G01X143200Y54100D02*
X140700D01*
X142492Y52558D01*
Y54642D01*
G01X176017Y92892D02*
X175767Y93017D01*
X175475Y93100D01*
X175142D01*
X174767Y92975D01*
X174475Y92767D01*
X174267Y92517D01*
X174100Y92100D01*
X174058Y91725D01*
X174142Y91350D01*
X174267Y91100D01*
X174517Y90850D01*
X174808Y90683D01*
X175100Y90600D01*
X175392D01*
X175683Y90683D01*
X175933Y90808D01*
X176142Y90975D01*
G01X177283D02*
X177533Y90767D01*
X177825Y90642D01*
X178200Y90600D01*
X178575Y90683D01*
X178867Y90850D01*
X179075Y91142D01*
X179117Y91475D01*
X179033Y91808D01*
X178825Y92017D01*
X178533Y92183D01*
X178242Y92225D01*
X177950Y92183D01*
X177575Y92017D01*
X177700Y93100D01*
X178825D01*
G01X180383Y91100D02*
X180633Y90808D01*
X180967Y90642D01*
X181342Y90600D01*
X181675Y90642D01*
X182008Y90850D01*
X182217Y91100D01*
X182258Y91350D01*
X182175Y91642D01*
X181883Y91850D01*
X181592Y91933D01*
X181217D01*
G01X181592D02*
X181842Y92058D01*
X182050Y92267D01*
X182133Y92517D01*
X182050Y92767D01*
X181842Y92975D01*
X181467Y93100D01*
X181092Y93058D01*
X180717Y92892D01*
G01X115798Y91357D02*
Y87357D01*
X123198D01*
G01X123220Y91564D02*
Y95564D01*
X115820D01*
G01X132367Y42800D02*
Y45300D01*
X133408D01*
X133742Y45175D01*
X133950Y45008D01*
X134033Y44675D01*
X133950Y44342D01*
X133700Y44133D01*
X133408Y44008D01*
X132367D01*
G01X133408D02*
X134033Y42800D01*
G01X135508Y43842D02*
X135800Y44133D01*
X136050Y44300D01*
X136383Y44383D01*
X136675Y44300D01*
X136883Y44133D01*
X137050Y43883D01*
X137092Y43592D01*
X137050Y43342D01*
X136883Y43092D01*
X136633Y42883D01*
X136342Y42800D01*
X136008Y42883D01*
X135717Y43133D01*
X135550Y43508D01*
X135508Y43925D01*
X135592Y44467D01*
X135717Y44758D01*
X135925Y45050D01*
X136217Y45258D01*
X136508Y45300D01*
X136800Y45217D01*
X137008Y45008D01*
G01X138692Y43092D02*
X138983Y42883D01*
X139317Y42800D01*
X139650Y42883D01*
X139942Y43133D01*
X140150Y43508D01*
X140233Y43883D01*
Y44342D01*
X140150Y44717D01*
X139942Y45050D01*
X139692Y45217D01*
X139400Y45300D01*
X139067Y45217D01*
X138817Y45050D01*
X138650Y44800D01*
X138567Y44467D01*
X138650Y44175D01*
X138858Y43883D01*
X139108Y43717D01*
X139400Y43675D01*
X139733Y43758D01*
X139983Y43967D01*
X140233Y44342D01*
G01X122600Y53900D02*
Y49900D01*
X130000D01*
G01X132367Y38600D02*
Y41100D01*
X133408D01*
X133742Y40975D01*
X133950Y40808D01*
X134033Y40475D01*
X133950Y40142D01*
X133700Y39933D01*
X133408Y39808D01*
X132367D01*
G01X133408D02*
X134033Y38600D01*
G01X136217D02*
X136300Y39142D01*
X136425Y39600D01*
X136592Y40017D01*
X136800Y40475D01*
X137133Y41100D01*
X135467D01*
G01X139400D02*
X139067Y41017D01*
X138817Y40808D01*
X138650Y40558D01*
X138525Y40225D01*
X138483Y39850D01*
X138525Y39475D01*
X138650Y39142D01*
X138817Y38892D01*
X139067Y38683D01*
X139400Y38600D01*
X139733Y38683D01*
X139983Y38892D01*
X140150Y39142D01*
X140275Y39475D01*
X140317Y39850D01*
X140275Y40225D01*
X140150Y40558D01*
X139983Y40808D01*
X139733Y41017D01*
X139400Y41100D01*
G01X122600Y49700D02*
Y45700D01*
X130000D01*
G01X132367Y34400D02*
Y36900D01*
X133408D01*
X133742Y36775D01*
X133950Y36608D01*
X134033Y36275D01*
X133950Y35942D01*
X133700Y35733D01*
X133408Y35608D01*
X132367D01*
G01X133408D02*
X134033Y34400D01*
G01X136217D02*
X136300Y34942D01*
X136425Y35400D01*
X136592Y35817D01*
X136800Y36275D01*
X137133Y36900D01*
X135467D01*
G01X138483Y34900D02*
X138733Y34608D01*
X139067Y34442D01*
X139442Y34400D01*
X139775Y34442D01*
X140108Y34650D01*
X140317Y34900D01*
X140358Y35150D01*
X140275Y35442D01*
X139983Y35650D01*
X139692Y35733D01*
X139317D01*
G01X139692D02*
X139942Y35858D01*
X140150Y36067D01*
X140233Y36317D01*
X140150Y36567D01*
X139942Y36775D01*
X139567Y36900D01*
X139192Y36858D01*
X138817Y36692D01*
G01X122600Y45500D02*
Y41500D01*
X130000D01*
G01X121067Y79100D02*
Y81600D01*
X122108D01*
X122442Y81475D01*
X122650Y81308D01*
X122733Y80975D01*
X122650Y80642D01*
X122400Y80433D01*
X122108Y80308D01*
X121067D01*
G01X122108D02*
X122733Y79100D01*
G01X124917D02*
X125000Y79642D01*
X125125Y80100D01*
X125292Y80517D01*
X125500Y80975D01*
X125833Y81600D01*
X124167D01*
G01X127308Y80142D02*
X127600Y80433D01*
X127850Y80600D01*
X128183Y80683D01*
X128475Y80600D01*
X128683Y80433D01*
X128850Y80183D01*
X128892Y79892D01*
X128850Y79642D01*
X128683Y79392D01*
X128433Y79183D01*
X128142Y79100D01*
X127808Y79183D01*
X127517Y79433D01*
X127350Y79808D01*
X127308Y80225D01*
X127392Y80767D01*
X127517Y81058D01*
X127725Y81350D01*
X128017Y81558D01*
X128308Y81600D01*
X128600Y81517D01*
X128808Y81308D01*
G01X127200Y72600D02*
Y76600D01*
X119800D01*
G01X110400Y76800D02*
Y72800D01*
X117800D01*
G01X164761Y61358D02*
Y63858D01*
X165802D01*
X166136Y63733D01*
X166344Y63566D01*
X166427Y63233D01*
X166344Y62900D01*
X166094Y62691D01*
X165802Y62566D01*
X164761D01*
G01X165802D02*
X166427Y61358D01*
G01X169194D02*
Y63858D01*
X167652Y62066D01*
X169736D01*
G01X170877Y61858D02*
X171127Y61566D01*
X171461Y61400D01*
X171836Y61358D01*
X172169Y61400D01*
X172502Y61608D01*
X172711Y61858D01*
X172752Y62108D01*
X172669Y62400D01*
X172377Y62608D01*
X172086Y62691D01*
X171711D01*
G01X172086D02*
X172336Y62816D01*
X172544Y63025D01*
X172627Y63275D01*
X172544Y63525D01*
X172336Y63733D01*
X171961Y63858D01*
X171586Y63816D01*
X171211Y63650D01*
G01X154900Y68400D02*
Y64400D01*
X162300D01*
G01X166983Y69834D02*
X164483D01*
Y70875D01*
X164608Y71209D01*
X164775Y71417D01*
X165108Y71500D01*
X165441Y71417D01*
X165650Y71167D01*
X165775Y70875D01*
Y69834D01*
G01Y70875D02*
X166983Y71500D01*
G01X165941Y72975D02*
X165650Y73267D01*
X165483Y73517D01*
X165400Y73850D01*
X165483Y74142D01*
X165650Y74350D01*
X165900Y74517D01*
X166191Y74559D01*
X166441Y74517D01*
X166691Y74350D01*
X166900Y74100D01*
X166983Y73809D01*
X166900Y73475D01*
X166650Y73184D01*
X166275Y73017D01*
X165858Y72975D01*
X165316Y73059D01*
X165025Y73184D01*
X164733Y73392D01*
X164525Y73684D01*
X164483Y73975D01*
X164566Y74267D01*
X164775Y74475D01*
G01X166608Y75950D02*
X166816Y76200D01*
X166941Y76492D01*
X166983Y76867D01*
X166900Y77242D01*
X166733Y77534D01*
X166441Y77742D01*
X166108Y77784D01*
X165775Y77700D01*
X165566Y77492D01*
X165400Y77200D01*
X165358Y76909D01*
X165400Y76617D01*
X165566Y76242D01*
X164483Y76367D01*
Y77492D01*
G01X159000Y76200D02*
X155000D01*
Y68800D01*
G01X147497Y43930D02*
X144997D01*
Y44971D01*
X145122Y45305D01*
X145289Y45513D01*
X145622Y45596D01*
X145955Y45513D01*
X146164Y45263D01*
X146289Y44971D01*
Y43930D01*
G01Y44971D02*
X147497Y45596D01*
G01Y47780D02*
X146955Y47863D01*
X146497Y47988D01*
X146080Y48155D01*
X145622Y48363D01*
X144997Y48696D01*
Y47030D01*
G01X147497Y51463D02*
X144997D01*
X146789Y49921D01*
Y52005D01*
G01X139000Y58300D02*
X135000D01*
Y50900D01*
G01X115458Y42544D02*
X112958D01*
Y43585D01*
X113083Y43919D01*
X113250Y44127D01*
X113583Y44210D01*
X113916Y44127D01*
X114125Y43877D01*
X114250Y43585D01*
Y42544D01*
G01Y43585D02*
X115458Y44210D01*
G01Y46394D02*
X114916Y46477D01*
X114458Y46602D01*
X114041Y46769D01*
X113583Y46977D01*
X112958Y47310D01*
Y45644D01*
G01X115166Y48869D02*
X115375Y49160D01*
X115458Y49494D01*
X115375Y49827D01*
X115125Y50119D01*
X114750Y50327D01*
X114375Y50410D01*
X113916D01*
X113541Y50327D01*
X113208Y50119D01*
X113041Y49869D01*
X112958Y49577D01*
X113041Y49244D01*
X113208Y48994D01*
X113458Y48827D01*
X113791Y48744D01*
X114083Y48827D01*
X114375Y49035D01*
X114541Y49285D01*
X114583Y49577D01*
X114500Y49910D01*
X114291Y50160D01*
X113916Y50410D01*
G01X115902Y100010D02*
Y96010D01*
X123302D01*
G01X149459Y54761D02*
Y52969D01*
X149626Y52594D01*
X149959Y52344D01*
X150376Y52261D01*
X150793Y52344D01*
X151126Y52594D01*
X151293Y52969D01*
Y54761D01*
G01X152559Y52636D02*
X152809Y52428D01*
X153101Y52303D01*
X153476Y52261D01*
X153851Y52344D01*
X154143Y52511D01*
X154351Y52803D01*
X154393Y53136D01*
X154309Y53469D01*
X154101Y53678D01*
X153809Y53844D01*
X153518Y53886D01*
X153226Y53844D01*
X152851Y53678D01*
X152976Y54761D01*
X154101D01*
G01X145800Y69400D02*
Y56000D01*
G01X147800Y69400D02*
X145800D01*
G01X147800Y56000D02*
Y69400D01*
G01X145800Y56000D02*
X147800D01*
G01X115600Y69400D02*
Y56000D01*
G01X117900Y55800D02*
Y69200D01*
G01X127900Y55800D02*
X117900D01*
G01X127900Y69200D02*
Y55800D01*
G01X117900Y69200D02*
X127900D01*
G01X183183Y97100D02*
Y95308D01*
X183350Y94933D01*
X183683Y94683D01*
X184100Y94600D01*
X184517Y94683D01*
X184850Y94933D01*
X185017Y95308D01*
Y97100D01*
G01X187200Y94600D02*
Y97100D01*
X186700Y96600D01*
G01Y94600D02*
X187700D01*
G01X190800D02*
Y97100D01*
X189258Y95308D01*
X191342D01*
G01X114575Y97664D02*
Y102664D01*
X109575D01*
G01X162150Y117000D02*
Y89000D01*
G01X126850Y93000D02*
Y113000D01*
G01X130850Y89000D02*
X126850Y93000D01*
G01X162150Y89000D02*
X130850D01*
G01X184330Y104443D02*
X184205Y104193D01*
X184122Y103901D01*
Y103568D01*
X184247Y103193D01*
X184455Y102901D01*
X184705Y102693D01*
X185122Y102526D01*
X185497Y102484D01*
X185872Y102568D01*
X186122Y102693D01*
X186372Y102943D01*
X186539Y103234D01*
X186622Y103526D01*
Y103818D01*
X186539Y104109D01*
X186414Y104359D01*
X186247Y104568D01*
G01X186622Y106626D02*
X184122D01*
X184622Y106126D01*
G01X186622D02*
Y107126D01*
G01X186122Y108809D02*
X186414Y109059D01*
X186580Y109393D01*
X186622Y109768D01*
X186580Y110101D01*
X186372Y110434D01*
X186122Y110643D01*
X185872Y110684D01*
X185580Y110601D01*
X185372Y110309D01*
X185289Y110018D01*
Y109643D01*
G01Y110018D02*
X185164Y110268D01*
X184955Y110476D01*
X184705Y110559D01*
X184455Y110476D01*
X184247Y110268D01*
X184122Y109893D01*
X184164Y109518D01*
X184330Y109143D01*
G01X176893Y106392D02*
X176768Y106142D01*
X176685Y105850D01*
Y105517D01*
X176810Y105142D01*
X177018Y104850D01*
X177268Y104642D01*
X177685Y104475D01*
X178060Y104433D01*
X178435Y104517D01*
X178685Y104642D01*
X178935Y104892D01*
X179102Y105183D01*
X179185Y105475D01*
Y105767D01*
X179102Y106058D01*
X178977Y106308D01*
X178810Y106517D01*
G01X179185Y108575D02*
X176685D01*
X177185Y108075D01*
G01X179185D02*
Y109075D01*
G01Y112175D02*
X176685D01*
X178477Y110633D01*
Y112717D01*
G01X114605Y107777D02*
Y111777D01*
X107205D01*
G01X167844Y116955D02*
Y119455D01*
X168885D01*
X169219Y119330D01*
X169427Y119163D01*
X169510Y118830D01*
X169427Y118497D01*
X169177Y118288D01*
X168885Y118163D01*
X167844D01*
G01X168885D02*
X169510Y116955D01*
G01X170860Y117455D02*
X171110Y117163D01*
X171444Y116997D01*
X171819Y116955D01*
X172152Y116997D01*
X172485Y117205D01*
X172694Y117455D01*
X172735Y117705D01*
X172652Y117997D01*
X172360Y118205D01*
X172069Y118288D01*
X171694D01*
G01X172069D02*
X172319Y118413D01*
X172527Y118622D01*
X172610Y118872D01*
X172527Y119122D01*
X172319Y119330D01*
X171944Y119455D01*
X171569Y119413D01*
X171194Y119247D01*
G01X174877Y119455D02*
X174544Y119372D01*
X174294Y119163D01*
X174127Y118913D01*
X174002Y118580D01*
X173960Y118205D01*
X174002Y117830D01*
X174127Y117497D01*
X174294Y117247D01*
X174544Y117038D01*
X174877Y116955D01*
X175210Y117038D01*
X175460Y117247D01*
X175627Y117497D01*
X175752Y117830D01*
X175794Y118205D01*
X175752Y118580D01*
X175627Y118913D01*
X175460Y119163D01*
X175210Y119372D01*
X174877Y119455D01*
G01X185500Y116500D02*
Y120500D01*
X178100D01*
G01X114671Y105765D02*
X118671D01*
Y113165D01*
G01X118998Y105771D02*
X122998D01*
Y113171D01*
G01X159120Y172365D02*
X156620D01*
Y173406D01*
X156745Y173740D01*
X156912Y173948D01*
X157245Y174031D01*
X157578Y173948D01*
X157787Y173698D01*
X157912Y173406D01*
Y172365D01*
G01Y173406D02*
X159120Y174031D01*
G01X158620Y175381D02*
X158912Y175631D01*
X159078Y175965D01*
X159120Y176340D01*
X159078Y176673D01*
X158870Y177006D01*
X158620Y177215D01*
X158370Y177256D01*
X158078Y177173D01*
X157870Y176881D01*
X157787Y176590D01*
Y176215D01*
G01Y176590D02*
X157662Y176840D01*
X157453Y177048D01*
X157203Y177131D01*
X156953Y177048D01*
X156745Y176840D01*
X156620Y176465D01*
X156662Y176090D01*
X156828Y175715D01*
G01X157037Y178606D02*
X156787Y178856D01*
X156662Y179148D01*
X156620Y179481D01*
X156703Y179898D01*
X156912Y180190D01*
X157162Y180273D01*
X157412Y180231D01*
X157620Y180065D01*
X158037Y179231D01*
X158328Y178856D01*
X158745Y178606D01*
X159120Y178523D01*
Y180273D01*
G01X177320Y178498D02*
X173320D01*
Y171098D01*
G01X155090Y172365D02*
X152590D01*
Y173406D01*
X152715Y173740D01*
X152882Y173948D01*
X153215Y174031D01*
X153548Y173948D01*
X153757Y173698D01*
X153882Y173406D01*
Y172365D01*
G01Y173406D02*
X155090Y174031D01*
G01X154590Y175381D02*
X154882Y175631D01*
X155048Y175965D01*
X155090Y176340D01*
X155048Y176673D01*
X154840Y177006D01*
X154590Y177215D01*
X154340Y177256D01*
X154048Y177173D01*
X153840Y176881D01*
X153757Y176590D01*
Y176215D01*
G01Y176590D02*
X153632Y176840D01*
X153423Y177048D01*
X153173Y177131D01*
X152923Y177048D01*
X152715Y176840D01*
X152590Y176465D01*
X152632Y176090D01*
X152798Y175715D01*
G01X155090Y179398D02*
X152590D01*
X153090Y178898D01*
G01X155090D02*
Y179898D01*
G01X173290Y178498D02*
X169290D01*
Y171098D01*
G01X163752Y162159D02*
X161252D01*
Y163200D01*
X161377Y163534D01*
X161544Y163742D01*
X161877Y163825D01*
X162210Y163742D01*
X162419Y163492D01*
X162544Y163200D01*
Y162159D01*
G01Y163200D02*
X163752Y163825D01*
G01X161669Y165300D02*
X161419Y165550D01*
X161294Y165842D01*
X161252Y166175D01*
X161335Y166592D01*
X161544Y166884D01*
X161794Y166967D01*
X162044Y166925D01*
X162252Y166759D01*
X162669Y165925D01*
X162960Y165550D01*
X163377Y165300D01*
X163752Y165217D01*
Y166967D01*
G01X161252Y169192D02*
X161335Y168859D01*
X161544Y168609D01*
X161794Y168442D01*
X162127Y168317D01*
X162502Y168275D01*
X162877Y168317D01*
X163210Y168442D01*
X163460Y168609D01*
X163669Y168859D01*
X163752Y169192D01*
X163669Y169525D01*
X163460Y169775D01*
X163210Y169942D01*
X162877Y170067D01*
X162502Y170109D01*
X162127Y170067D01*
X161794Y169942D01*
X161544Y169775D01*
X161335Y169525D01*
X161252Y169192D01*
G01X161669Y171500D02*
X161419Y171750D01*
X161294Y172042D01*
X161252Y172375D01*
X161335Y172792D01*
X161544Y173084D01*
X161794Y173167D01*
X162044Y173125D01*
X162252Y172959D01*
X162669Y172125D01*
X162960Y171750D01*
X163377Y171500D01*
X163752Y171417D01*
Y173167D01*
G01X179152Y164642D02*
X183152D01*
Y172042D01*
G01X168000Y162017D02*
X165500D01*
Y163058D01*
X165625Y163392D01*
X165792Y163600D01*
X166125Y163683D01*
X166458Y163600D01*
X166667Y163350D01*
X166792Y163058D01*
Y162017D01*
G01Y163058D02*
X168000Y163683D01*
G01X165917Y165158D02*
X165667Y165408D01*
X165542Y165700D01*
X165500Y166033D01*
X165583Y166450D01*
X165792Y166742D01*
X166042Y166825D01*
X166292Y166783D01*
X166500Y166617D01*
X166917Y165783D01*
X167208Y165408D01*
X167625Y165158D01*
X168000Y165075D01*
Y166825D01*
G01X165500Y169050D02*
X165583Y168717D01*
X165792Y168467D01*
X166042Y168300D01*
X166375Y168175D01*
X166750Y168133D01*
X167125Y168175D01*
X167458Y168300D01*
X167708Y168467D01*
X167917Y168717D01*
X168000Y169050D01*
X167917Y169383D01*
X167708Y169633D01*
X167458Y169800D01*
X167125Y169925D01*
X166750Y169967D01*
X166375Y169925D01*
X166042Y169800D01*
X165792Y169633D01*
X165583Y169383D01*
X165500Y169050D01*
G01X168000Y172150D02*
X165500D01*
X166000Y171650D01*
G01X168000D02*
Y172650D01*
G01X183182Y164642D02*
X187182D01*
Y172042D01*
G01X109568Y122089D02*
Y159089D01*
X461968D01*
Y122089D01*
X109568D01*
G01X107641Y101770D02*
Y103770D01*
G01X130850Y117000D02*
X162150D01*
G01X126850Y113000D02*
X130850Y117000D01*
G01X113750Y163100D02*
Y191100D01*
G01X145050Y163100D02*
X113750D01*
G01X149050Y167100D02*
X145050Y163100D01*
G01X149050Y187100D02*
Y167100D01*
G01X175308Y185417D02*
X175183Y185167D01*
X175100Y184875D01*
Y184542D01*
X175225Y184167D01*
X175433Y183875D01*
X175683Y183667D01*
X176100Y183500D01*
X176475Y183458D01*
X176850Y183542D01*
X177100Y183667D01*
X177350Y183917D01*
X177517Y184208D01*
X177600Y184500D01*
Y184792D01*
X177517Y185083D01*
X177392Y185333D01*
X177225Y185542D01*
G01X175517Y186808D02*
X175267Y187058D01*
X175142Y187350D01*
X175100Y187683D01*
X175183Y188100D01*
X175392Y188392D01*
X175642Y188475D01*
X175892Y188433D01*
X176100Y188267D01*
X176517Y187433D01*
X176808Y187058D01*
X177225Y186808D01*
X177600Y186725D01*
Y188475D01*
G01Y190617D02*
X177058Y190700D01*
X176600Y190825D01*
X176183Y190992D01*
X175725Y191200D01*
X175100Y191533D01*
Y189867D01*
G01X145017Y197500D02*
Y200000D01*
X146058D01*
X146392Y199875D01*
X146600Y199708D01*
X146683Y199375D01*
X146600Y199042D01*
X146350Y198833D01*
X146058Y198708D01*
X145017D01*
G01X146058D02*
X146683Y197500D01*
G01X148950D02*
Y200000D01*
X148450Y199500D01*
G01Y197500D02*
X149450D01*
G01X152050Y200000D02*
X151717Y199917D01*
X151467Y199708D01*
X151300Y199458D01*
X151175Y199125D01*
X151133Y198750D01*
X151175Y198375D01*
X151300Y198042D01*
X151467Y197792D01*
X151717Y197583D01*
X152050Y197500D01*
X152383Y197583D01*
X152633Y197792D01*
X152800Y198042D01*
X152925Y198375D01*
X152967Y198750D01*
X152925Y199125D01*
X152800Y199458D01*
X152633Y199708D01*
X152383Y199917D01*
X152050Y200000D01*
G01X154233Y197875D02*
X154483Y197667D01*
X154775Y197542D01*
X155150Y197500D01*
X155525Y197583D01*
X155817Y197750D01*
X156025Y198042D01*
X156067Y198375D01*
X155983Y198708D01*
X155775Y198917D01*
X155483Y199083D01*
X155192Y199125D01*
X154900Y199083D01*
X154525Y198917D01*
X154650Y200000D01*
X155775D01*
G01X162754Y200330D02*
Y196330D01*
X170154D01*
G01X181167Y197400D02*
Y199900D01*
X182208D01*
X182542Y199775D01*
X182750Y199608D01*
X182833Y199275D01*
X182750Y198942D01*
X182500Y198733D01*
X182208Y198608D01*
X181167D01*
G01X182208D02*
X182833Y197400D01*
G01X184183Y197900D02*
X184433Y197608D01*
X184767Y197442D01*
X185142Y197400D01*
X185475Y197442D01*
X185808Y197650D01*
X186017Y197900D01*
X186058Y198150D01*
X185975Y198442D01*
X185683Y198650D01*
X185392Y198733D01*
X185017D01*
G01X185392D02*
X185642Y198858D01*
X185850Y199067D01*
X185933Y199317D01*
X185850Y199567D01*
X185642Y199775D01*
X185267Y199900D01*
X184892Y199858D01*
X184517Y199692D01*
G01X187283Y197775D02*
X187533Y197567D01*
X187825Y197442D01*
X188200Y197400D01*
X188575Y197483D01*
X188867Y197650D01*
X189075Y197942D01*
X189117Y198275D01*
X189033Y198608D01*
X188825Y198817D01*
X188533Y198983D01*
X188242Y199025D01*
X187950Y198983D01*
X187575Y198817D01*
X187700Y199900D01*
X188825D01*
G01X177726Y196299D02*
Y200299D01*
X170326D01*
G01X181780Y183649D02*
X179280D01*
Y184690D01*
X179405Y185024D01*
X179572Y185232D01*
X179905Y185315D01*
X180238Y185232D01*
X180447Y184982D01*
X180572Y184690D01*
Y183649D01*
G01Y184690D02*
X181780Y185315D01*
G01Y187582D02*
X179280D01*
X179780Y187082D01*
G01X181780D02*
Y188082D01*
G01X179697Y189890D02*
X179447Y190140D01*
X179322Y190432D01*
X179280Y190765D01*
X179363Y191182D01*
X179572Y191474D01*
X179822Y191557D01*
X180072Y191515D01*
X180280Y191349D01*
X180697Y190515D01*
X180988Y190140D01*
X181405Y189890D01*
X181780Y189807D01*
Y191557D01*
G01X179280Y193782D02*
X179363Y193449D01*
X179572Y193199D01*
X179822Y193032D01*
X180155Y192907D01*
X180530Y192865D01*
X180905Y192907D01*
X181238Y193032D01*
X181488Y193199D01*
X181697Y193449D01*
X181780Y193782D01*
X181697Y194115D01*
X181488Y194365D01*
X181238Y194532D01*
X180905Y194657D01*
X180530Y194699D01*
X180155Y194657D01*
X179822Y194532D01*
X179572Y194365D01*
X179363Y194115D01*
X179280Y193782D01*
G01X173300Y191600D02*
X169300D01*
Y184200D01*
G01X109568Y202089D02*
Y239089D01*
X461968D01*
Y202089D01*
X109568D01*
G01X129400Y195500D02*
Y193000D01*
G01X128442Y195500D02*
X130358D01*
G01X133417Y195292D02*
X133167Y195417D01*
X132875Y195500D01*
X132542D01*
X132167Y195375D01*
X131875Y195167D01*
X131667Y194917D01*
X131500Y194500D01*
X131458Y194125D01*
X131542Y193750D01*
X131667Y193500D01*
X131917Y193250D01*
X132208Y193083D01*
X132500Y193000D01*
X132792D01*
X133083Y193083D01*
X133333Y193208D01*
X133542Y193375D01*
G01X135600Y193000D02*
Y195500D01*
X135100Y195000D01*
G01Y193000D02*
X136100D01*
G01X145050Y191100D02*
X149050Y187100D01*
G01X113750Y191100D02*
X145050D01*
G01X158408Y185817D02*
X158283Y185567D01*
X158200Y185275D01*
Y184942D01*
X158325Y184567D01*
X158533Y184275D01*
X158783Y184067D01*
X159200Y183900D01*
X159575Y183858D01*
X159950Y183942D01*
X160200Y184067D01*
X160450Y184317D01*
X160617Y184608D01*
X160700Y184900D01*
Y185192D01*
X160617Y185483D01*
X160492Y185733D01*
X160325Y185942D01*
G01X158617Y187208D02*
X158367Y187458D01*
X158242Y187750D01*
X158200Y188083D01*
X158283Y188500D01*
X158492Y188792D01*
X158742Y188875D01*
X158992Y188833D01*
X159200Y188667D01*
X159617Y187833D01*
X159908Y187458D01*
X160325Y187208D01*
X160700Y187125D01*
Y188875D01*
G01X159658Y190308D02*
X159367Y190600D01*
X159200Y190850D01*
X159117Y191183D01*
X159200Y191475D01*
X159367Y191683D01*
X159617Y191850D01*
X159908Y191892D01*
X160158Y191850D01*
X160408Y191683D01*
X160617Y191433D01*
X160700Y191142D01*
X160617Y190808D01*
X160367Y190517D01*
X159992Y190350D01*
X159575Y190308D01*
X159033Y190392D01*
X158742Y190517D01*
X158450Y190725D01*
X158242Y191017D01*
X158200Y191308D01*
X158283Y191600D01*
X158492Y191808D01*
G01X126179Y273781D02*
X125679Y273281D01*
X125079Y273081D01*
X124379Y272981D01*
X123579Y273081D01*
X122979Y273581D01*
X122779Y274081D01*
X122879Y274581D01*
X123179Y274981D01*
X124879Y275781D01*
X125679Y276381D01*
X126179Y277181D01*
X126279Y277981D01*
X122779D01*
G01X130179Y272981D02*
X130779Y273081D01*
X131279Y273581D01*
X131679Y274081D01*
X131879Y274681D01*
X131979Y275481D01*
X131879Y276181D01*
X131679Y276881D01*
X131279Y277381D01*
X130779Y277781D01*
X130179Y277981D01*
X129479Y277781D01*
X128979Y277381D01*
X128679Y276881D01*
X128379Y276181D01*
X128279Y275481D01*
X128379Y274681D01*
X128679Y274081D01*
X128979Y273581D01*
X129479Y273081D01*
X130179Y272981D01*
G01X133679Y279381D02*
Y271581D01*
X121079D01*
Y279381D01*
X133679D01*
G01X406900Y62200D02*
Y49100D01*
X409500D01*
Y39600D01*
X413100D01*
Y35700D01*
X406900D01*
Y-5000D01*
X332300D01*
Y16100D01*
X319700D01*
Y20600D01*
X265700D01*
Y110100D01*
X325800D01*
Y86300D01*
X403700D01*
Y74600D01*
X409600D01*
Y67900D01*
G01X200165Y88857D02*
Y91357D01*
X201206D01*
X201540Y91232D01*
X201748Y91065D01*
X201831Y90732D01*
X201748Y90399D01*
X201498Y90190D01*
X201206Y90065D01*
X200165D01*
G01X201206D02*
X201831Y88857D01*
G01X204098D02*
X204390Y88899D01*
X204723Y89024D01*
X204931Y89232D01*
X205015Y89524D01*
X204931Y89815D01*
X204681Y90065D01*
X204306Y90190D01*
X203890D01*
X203640Y90274D01*
X203431Y90482D01*
X203348Y90774D01*
X203473Y91065D01*
X203765Y91274D01*
X204098Y91357D01*
X204431Y91274D01*
X204723Y91065D01*
X204848Y90774D01*
X204765Y90482D01*
X204556Y90274D01*
X204306Y90190D01*
X203890D01*
X203515Y90065D01*
X203265Y89815D01*
X203181Y89524D01*
X203265Y89232D01*
X203473Y89024D01*
X203806Y88899D01*
X204098Y88857D01*
G01X207698D02*
Y91357D01*
X206156Y89565D01*
X208240D01*
G01X200187Y93064D02*
Y95564D01*
X201228D01*
X201562Y95439D01*
X201770Y95272D01*
X201853Y94939D01*
X201770Y94606D01*
X201520Y94397D01*
X201228Y94272D01*
X200187D01*
G01X201228D02*
X201853Y93064D01*
G01X204120D02*
X204412Y93106D01*
X204745Y93231D01*
X204953Y93439D01*
X205037Y93731D01*
X204953Y94022D01*
X204703Y94272D01*
X204328Y94397D01*
X203912D01*
X203662Y94481D01*
X203453Y94689D01*
X203370Y94981D01*
X203495Y95272D01*
X203787Y95481D01*
X204120Y95564D01*
X204453Y95481D01*
X204745Y95272D01*
X204870Y94981D01*
X204787Y94689D01*
X204578Y94481D01*
X204328Y94397D01*
X203912D01*
X203537Y94272D01*
X203287Y94022D01*
X203203Y93731D01*
X203287Y93439D01*
X203495Y93231D01*
X203828Y93106D01*
X204120Y93064D01*
G01X206303Y93439D02*
X206553Y93231D01*
X206845Y93106D01*
X207220Y93064D01*
X207595Y93147D01*
X207887Y93314D01*
X208095Y93606D01*
X208137Y93939D01*
X208053Y94272D01*
X207845Y94481D01*
X207553Y94647D01*
X207262Y94689D01*
X206970Y94647D01*
X206595Y94481D01*
X206720Y95564D01*
X207845D01*
G01X202019Y98510D02*
Y101010D01*
X203060D01*
X203394Y100885D01*
X203602Y100718D01*
X203685Y100385D01*
X203602Y100052D01*
X203352Y99843D01*
X203060Y99718D01*
X202019D01*
G01X203060D02*
X203685Y98510D01*
G01X205952D02*
Y101010D01*
X205452Y100510D01*
G01Y98510D02*
X206452D01*
G01X208260Y99552D02*
X208552Y99843D01*
X208802Y100010D01*
X209135Y100093D01*
X209427Y100010D01*
X209635Y99843D01*
X209802Y99593D01*
X209844Y99302D01*
X209802Y99052D01*
X209635Y98802D01*
X209385Y98593D01*
X209094Y98510D01*
X208760Y98593D01*
X208469Y98843D01*
X208302Y99218D01*
X208260Y99635D01*
X208344Y100177D01*
X208469Y100468D01*
X208677Y100760D01*
X208969Y100968D01*
X209260Y101010D01*
X209552Y100927D01*
X209760Y100718D01*
G01X212652Y98510D02*
Y101010D01*
X211110Y99218D01*
X213194D01*
G01X213817Y109392D02*
X213567Y109517D01*
X213275Y109600D01*
X212942D01*
X212567Y109475D01*
X212275Y109267D01*
X212067Y109017D01*
X211900Y108600D01*
X211858Y108225D01*
X211942Y107850D01*
X212067Y107600D01*
X212317Y107350D01*
X212608Y107183D01*
X212900Y107100D01*
X213192D01*
X213483Y107183D01*
X213733Y107308D01*
X213942Y107475D01*
G01X215208Y109183D02*
X215458Y109433D01*
X215750Y109558D01*
X216083Y109600D01*
X216500Y109517D01*
X216792Y109308D01*
X216875Y109058D01*
X216833Y108808D01*
X216667Y108600D01*
X215833Y108183D01*
X215458Y107892D01*
X215208Y107475D01*
X215125Y107100D01*
X216875D01*
G01X219100D02*
Y109600D01*
X218600Y109100D01*
G01Y107100D02*
X219600D01*
G01X202917Y115900D02*
Y118400D01*
X203958D01*
X204292Y118275D01*
X204500Y118108D01*
X204583Y117775D01*
X204500Y117442D01*
X204250Y117233D01*
X203958Y117108D01*
X202917D01*
G01X203958D02*
X204583Y115900D01*
G01X206850D02*
Y118400D01*
X206350Y117900D01*
G01Y115900D02*
X207350D01*
G01X209950Y118400D02*
X209617Y118317D01*
X209367Y118108D01*
X209200Y117858D01*
X209075Y117525D01*
X209033Y117150D01*
X209075Y116775D01*
X209200Y116442D01*
X209367Y116192D01*
X209617Y115983D01*
X209950Y115900D01*
X210283Y115983D01*
X210533Y116192D01*
X210700Y116442D01*
X210825Y116775D01*
X210867Y117150D01*
X210825Y117525D01*
X210700Y117858D01*
X210533Y118108D01*
X210283Y118317D01*
X209950Y118400D01*
G01X212258Y117983D02*
X212508Y118233D01*
X212800Y118358D01*
X213133Y118400D01*
X213550Y118317D01*
X213842Y118108D01*
X213925Y117858D01*
X213883Y117608D01*
X213717Y117400D01*
X212883Y116983D01*
X212508Y116692D01*
X212258Y116275D01*
X212175Y115900D01*
X213925D01*
G01X199413Y114998D02*
Y118998D01*
X192013D01*
G01X249417Y115900D02*
Y118400D01*
X250458D01*
X250792Y118275D01*
X251000Y118108D01*
X251083Y117775D01*
X251000Y117442D01*
X250750Y117233D01*
X250458Y117108D01*
X249417D01*
G01X250458D02*
X251083Y115900D01*
G01X253350D02*
Y118400D01*
X252850Y117900D01*
G01Y115900D02*
X253850D01*
G01X256450Y118400D02*
X256117Y118317D01*
X255867Y118108D01*
X255700Y117858D01*
X255575Y117525D01*
X255533Y117150D01*
X255575Y116775D01*
X255700Y116442D01*
X255867Y116192D01*
X256117Y115983D01*
X256450Y115900D01*
X256783Y115983D01*
X257033Y116192D01*
X257200Y116442D01*
X257325Y116775D01*
X257367Y117150D01*
X257325Y117525D01*
X257200Y117858D01*
X257033Y118108D01*
X256783Y118317D01*
X256450Y118400D01*
G01X258633Y116400D02*
X258883Y116108D01*
X259217Y115942D01*
X259592Y115900D01*
X259925Y115942D01*
X260258Y116150D01*
X260467Y116400D01*
X260508Y116650D01*
X260425Y116942D01*
X260133Y117150D01*
X259842Y117233D01*
X259467D01*
G01X259842D02*
X260092Y117358D01*
X260300Y117567D01*
X260383Y117817D01*
X260300Y118067D01*
X260092Y118275D01*
X259717Y118400D01*
X259342Y118358D01*
X258967Y118192D01*
G01X246800Y115600D02*
Y119600D01*
X239400D01*
G01X188532Y102630D02*
Y105130D01*
X189573D01*
X189907Y105005D01*
X190115Y104838D01*
X190198Y104505D01*
X190115Y104172D01*
X189865Y103963D01*
X189573Y103838D01*
X188532D01*
G01X189573D02*
X190198Y102630D01*
G01X191673Y103672D02*
X191965Y103963D01*
X192215Y104130D01*
X192548Y104213D01*
X192840Y104130D01*
X193048Y103963D01*
X193215Y103713D01*
X193257Y103422D01*
X193215Y103172D01*
X193048Y102922D01*
X192798Y102713D01*
X192507Y102630D01*
X192173Y102713D01*
X191882Y102963D01*
X191715Y103338D01*
X191673Y103755D01*
X191757Y104297D01*
X191882Y104588D01*
X192090Y104880D01*
X192382Y105088D01*
X192673Y105130D01*
X192965Y105047D01*
X193173Y104838D01*
G01X196065Y102630D02*
Y105130D01*
X194523Y103338D01*
X196607D01*
G01X188467Y106800D02*
Y109300D01*
X189508D01*
X189842Y109175D01*
X190050Y109008D01*
X190133Y108675D01*
X190050Y108342D01*
X189800Y108133D01*
X189508Y108008D01*
X188467D01*
G01X189508D02*
X190133Y106800D01*
G01X192400D02*
X192692Y106842D01*
X193025Y106967D01*
X193233Y107175D01*
X193317Y107467D01*
X193233Y107758D01*
X192983Y108008D01*
X192608Y108133D01*
X192192D01*
X191942Y108217D01*
X191733Y108425D01*
X191650Y108717D01*
X191775Y109008D01*
X192067Y109217D01*
X192400Y109300D01*
X192733Y109217D01*
X193025Y109008D01*
X193150Y108717D01*
X193067Y108425D01*
X192858Y108217D01*
X192608Y108133D01*
X192192D01*
X191817Y108008D01*
X191567Y107758D01*
X191483Y107467D01*
X191567Y107175D01*
X191775Y106967D01*
X192108Y106842D01*
X192400Y106800D01*
G01X194708Y108883D02*
X194958Y109133D01*
X195250Y109258D01*
X195583Y109300D01*
X196000Y109217D01*
X196292Y109008D01*
X196375Y108758D01*
X196333Y108508D01*
X196167Y108300D01*
X195333Y107883D01*
X194958Y107592D01*
X194708Y107175D01*
X194625Y106800D01*
X196375D01*
G01X200871Y102932D02*
X198371D01*
Y103973D01*
X198496Y104307D01*
X198663Y104515D01*
X198996Y104598D01*
X199329Y104515D01*
X199538Y104265D01*
X199663Y103973D01*
Y102932D01*
G01Y103973D02*
X200871Y104598D01*
G01Y107365D02*
X198371D01*
X200163Y105823D01*
Y107907D01*
G01X198371Y109965D02*
X198454Y109632D01*
X198663Y109382D01*
X198913Y109215D01*
X199246Y109090D01*
X199621Y109048D01*
X199996Y109090D01*
X200329Y109215D01*
X200579Y109382D01*
X200788Y109632D01*
X200871Y109965D01*
X200788Y110298D01*
X200579Y110548D01*
X200329Y110715D01*
X199996Y110840D01*
X199621Y110882D01*
X199246Y110840D01*
X198913Y110715D01*
X198663Y110548D01*
X198454Y110298D01*
X198371Y109965D01*
G01X205198Y102938D02*
X202698D01*
Y103979D01*
X202823Y104313D01*
X202990Y104521D01*
X203323Y104604D01*
X203656Y104521D01*
X203865Y104271D01*
X203990Y103979D01*
Y102938D01*
G01Y103979D02*
X205198Y104604D01*
G01X204156Y106079D02*
X203865Y106371D01*
X203698Y106621D01*
X203615Y106954D01*
X203698Y107246D01*
X203865Y107454D01*
X204115Y107621D01*
X204406Y107663D01*
X204656Y107621D01*
X204906Y107454D01*
X205115Y107204D01*
X205198Y106913D01*
X205115Y106579D01*
X204865Y106288D01*
X204490Y106121D01*
X204073Y106079D01*
X203531Y106163D01*
X203240Y106288D01*
X202948Y106496D01*
X202740Y106788D01*
X202698Y107079D01*
X202781Y107371D01*
X202990Y107579D01*
G01X204698Y109054D02*
X204990Y109304D01*
X205156Y109638D01*
X205198Y110013D01*
X205156Y110346D01*
X204948Y110679D01*
X204698Y110888D01*
X204448Y110929D01*
X204156Y110846D01*
X203948Y110554D01*
X203865Y110263D01*
Y109888D01*
G01Y110263D02*
X203740Y110513D01*
X203531Y110721D01*
X203281Y110804D01*
X203031Y110721D01*
X202823Y110513D01*
X202698Y110138D01*
X202740Y109763D01*
X202906Y109388D01*
G01X215665Y169920D02*
Y172420D01*
X216706D01*
X217040Y172295D01*
X217248Y172128D01*
X217331Y171795D01*
X217248Y171462D01*
X216998Y171253D01*
X216706Y171128D01*
X215665D01*
G01X216706D02*
X217331Y169920D01*
G01X218681Y170420D02*
X218931Y170128D01*
X219265Y169962D01*
X219640Y169920D01*
X219973Y169962D01*
X220306Y170170D01*
X220515Y170420D01*
X220556Y170670D01*
X220473Y170962D01*
X220181Y171170D01*
X219890Y171253D01*
X219515D01*
G01X219890D02*
X220140Y171378D01*
X220348Y171587D01*
X220431Y171837D01*
X220348Y172087D01*
X220140Y172295D01*
X219765Y172420D01*
X219390Y172378D01*
X219015Y172212D01*
G01X222615Y169920D02*
X222698Y170462D01*
X222823Y170920D01*
X222990Y171337D01*
X223198Y171795D01*
X223531Y172420D01*
X221865D01*
G01X232098Y169220D02*
Y173220D01*
X224698D01*
G01X215765Y174350D02*
Y176850D01*
X216806D01*
X217140Y176725D01*
X217348Y176558D01*
X217431Y176225D01*
X217348Y175892D01*
X217098Y175683D01*
X216806Y175558D01*
X215765D01*
G01X216806D02*
X217431Y174350D01*
G01X218781Y174850D02*
X219031Y174558D01*
X219365Y174392D01*
X219740Y174350D01*
X220073Y174392D01*
X220406Y174600D01*
X220615Y174850D01*
X220656Y175100D01*
X220573Y175392D01*
X220281Y175600D01*
X219990Y175683D01*
X219615D01*
G01X219990D02*
X220240Y175808D01*
X220448Y176017D01*
X220531Y176267D01*
X220448Y176517D01*
X220240Y176725D01*
X219865Y176850D01*
X219490Y176808D01*
X219115Y176642D01*
G01X222006Y175392D02*
X222298Y175683D01*
X222548Y175850D01*
X222881Y175933D01*
X223173Y175850D01*
X223381Y175683D01*
X223548Y175433D01*
X223590Y175142D01*
X223548Y174892D01*
X223381Y174642D01*
X223131Y174433D01*
X222840Y174350D01*
X222506Y174433D01*
X222215Y174683D01*
X222048Y175058D01*
X222006Y175475D01*
X222090Y176017D01*
X222215Y176308D01*
X222423Y176600D01*
X222715Y176808D01*
X223006Y176850D01*
X223298Y176767D01*
X223506Y176558D01*
G01X232098Y173550D02*
Y177550D01*
X224698D01*
G01X254600Y173967D02*
X252100D01*
Y175008D01*
X252225Y175342D01*
X252392Y175550D01*
X252725Y175633D01*
X253058Y175550D01*
X253267Y175300D01*
X253392Y175008D01*
Y173967D01*
G01Y175008D02*
X254600Y175633D01*
G01X254225Y176983D02*
X254433Y177233D01*
X254558Y177525D01*
X254600Y177900D01*
X254517Y178275D01*
X254350Y178567D01*
X254058Y178775D01*
X253725Y178817D01*
X253392Y178733D01*
X253183Y178525D01*
X253017Y178233D01*
X252975Y177942D01*
X253017Y177650D01*
X253183Y177275D01*
X252100Y177400D01*
Y178525D01*
G01X252517Y180208D02*
X252267Y180458D01*
X252142Y180750D01*
X252100Y181083D01*
X252183Y181500D01*
X252392Y181792D01*
X252642Y181875D01*
X252892Y181833D01*
X253100Y181667D01*
X253517Y180833D01*
X253808Y180458D01*
X254225Y180208D01*
X254600Y180125D01*
Y181875D01*
G01X239900Y163567D02*
X237400D01*
Y164608D01*
X237525Y164942D01*
X237692Y165150D01*
X238025Y165233D01*
X238358Y165150D01*
X238567Y164900D01*
X238692Y164608D01*
Y163567D01*
G01Y164608D02*
X239900Y165233D01*
G01X237817Y166708D02*
X237567Y166958D01*
X237442Y167250D01*
X237400Y167583D01*
X237483Y168000D01*
X237692Y168292D01*
X237942Y168375D01*
X238192Y168333D01*
X238400Y168167D01*
X238817Y167333D01*
X239108Y166958D01*
X239525Y166708D01*
X239900Y166625D01*
Y168375D01*
G01Y170600D02*
X237400D01*
X237900Y170100D01*
G01X239900D02*
Y171100D01*
G01X232200Y166000D02*
X236200D01*
Y173400D01*
G01X249267Y167400D02*
Y169900D01*
X250308D01*
X250642Y169775D01*
X250850Y169608D01*
X250933Y169275D01*
X250850Y168942D01*
X250600Y168733D01*
X250308Y168608D01*
X249267D01*
G01X250308D02*
X250933Y167400D01*
G01X252408Y169483D02*
X252658Y169733D01*
X252950Y169858D01*
X253283Y169900D01*
X253700Y169817D01*
X253992Y169608D01*
X254075Y169358D01*
X254033Y169108D01*
X253867Y168900D01*
X253033Y168483D01*
X252658Y168192D01*
X252408Y167775D01*
X252325Y167400D01*
X254075D01*
G01X256300Y169900D02*
X255967Y169817D01*
X255717Y169608D01*
X255550Y169358D01*
X255425Y169025D01*
X255383Y168650D01*
X255425Y168275D01*
X255550Y167942D01*
X255717Y167692D01*
X255967Y167483D01*
X256300Y167400D01*
X256633Y167483D01*
X256883Y167692D01*
X257050Y167942D01*
X257175Y168275D01*
X257217Y168650D01*
X257175Y169025D01*
X257050Y169358D01*
X256883Y169608D01*
X256633Y169817D01*
X256300Y169900D01*
G01X241000Y182600D02*
Y178600D01*
X248400D01*
G01X239700Y172867D02*
X237200D01*
Y173908D01*
X237325Y174242D01*
X237492Y174450D01*
X237825Y174533D01*
X238158Y174450D01*
X238367Y174200D01*
X238492Y173908D01*
Y172867D01*
G01Y173908D02*
X239700Y174533D01*
G01X237617Y176008D02*
X237367Y176258D01*
X237242Y176550D01*
X237200Y176883D01*
X237283Y177300D01*
X237492Y177592D01*
X237742Y177675D01*
X237992Y177633D01*
X238200Y177467D01*
X238617Y176633D01*
X238908Y176258D01*
X239325Y176008D01*
X239700Y175925D01*
Y177675D01*
G01X237617Y179108D02*
X237367Y179358D01*
X237242Y179650D01*
X237200Y179983D01*
X237283Y180400D01*
X237492Y180692D01*
X237742Y180775D01*
X237992Y180733D01*
X238200Y180567D01*
X238617Y179733D01*
X238908Y179358D01*
X239325Y179108D01*
X239700Y179025D01*
Y180775D01*
G01X236300Y181100D02*
X232300D01*
Y173700D01*
G01X249267Y163300D02*
Y165800D01*
X250308D01*
X250642Y165675D01*
X250850Y165508D01*
X250933Y165175D01*
X250850Y164842D01*
X250600Y164633D01*
X250308Y164508D01*
X249267D01*
G01X250308D02*
X250933Y163300D01*
G01X253200D02*
Y165800D01*
X252700Y165300D01*
G01Y163300D02*
X253700D01*
G01X255592Y163592D02*
X255883Y163383D01*
X256217Y163300D01*
X256550Y163383D01*
X256842Y163633D01*
X257050Y164008D01*
X257133Y164383D01*
Y164842D01*
X257050Y165217D01*
X256842Y165550D01*
X256592Y165717D01*
X256300Y165800D01*
X255967Y165717D01*
X255717Y165550D01*
X255550Y165300D01*
X255467Y164967D01*
X255550Y164675D01*
X255758Y164383D01*
X256008Y164217D01*
X256300Y164175D01*
X256633Y164258D01*
X256883Y164467D01*
X257133Y164842D01*
G01X241000Y178500D02*
Y174500D01*
X248400D01*
G01X210600Y175183D02*
X212392D01*
X212767Y175350D01*
X213017Y175683D01*
X213100Y176100D01*
X213017Y176517D01*
X212767Y176850D01*
X212392Y177017D01*
X210600D01*
G01X211017Y178408D02*
X210767Y178658D01*
X210642Y178950D01*
X210600Y179283D01*
X210683Y179700D01*
X210892Y179992D01*
X211142Y180075D01*
X211392Y180033D01*
X211600Y179867D01*
X212017Y179033D01*
X212308Y178658D01*
X212725Y178408D01*
X213100Y178325D01*
Y180075D01*
G01X212600Y181383D02*
X212892Y181633D01*
X213058Y181967D01*
X213100Y182342D01*
X213058Y182675D01*
X212850Y183008D01*
X212600Y183217D01*
X212350Y183258D01*
X212058Y183175D01*
X211850Y182883D01*
X211767Y182592D01*
Y182217D01*
G01Y182592D02*
X211642Y182842D01*
X211433Y183050D01*
X211183Y183133D01*
X210933Y183050D01*
X210725Y182842D01*
X210600Y182467D01*
X210642Y182092D01*
X210808Y181717D01*
G01X206190Y176498D02*
Y184498D01*
X194240D01*
Y176498D01*
X206190D01*
G01X194240Y182648D02*
X196240Y180648D01*
X194240Y178648D01*
G01X208000Y103600D02*
X210500D01*
G01X208000Y102642D02*
Y104558D01*
G01X208208Y107617D02*
X208083Y107367D01*
X208000Y107075D01*
Y106742D01*
X208125Y106367D01*
X208333Y106075D01*
X208583Y105867D01*
X209000Y105700D01*
X209375Y105658D01*
X209750Y105742D01*
X210000Y105867D01*
X210250Y106117D01*
X210417Y106408D01*
X210500Y106700D01*
Y106992D01*
X210417Y107283D01*
X210292Y107533D01*
X210125Y107742D01*
G01X210500Y110300D02*
X208000D01*
X209792Y108758D01*
Y110842D01*
G01X214317Y105192D02*
X214067Y105317D01*
X213775Y105400D01*
X213442D01*
X213067Y105275D01*
X212775Y105067D01*
X212567Y104817D01*
X212400Y104400D01*
X212358Y104025D01*
X212442Y103650D01*
X212567Y103400D01*
X212817Y103150D01*
X213108Y102983D01*
X213400Y102900D01*
X213692D01*
X213983Y102983D01*
X214233Y103108D01*
X214442Y103275D01*
G01X215708Y104983D02*
X215958Y105233D01*
X216250Y105358D01*
X216583Y105400D01*
X217000Y105317D01*
X217292Y105108D01*
X217375Y104858D01*
X217333Y104608D01*
X217167Y104400D01*
X216333Y103983D01*
X215958Y103692D01*
X215708Y103275D01*
X215625Y102900D01*
X217375D01*
G01X219600Y105400D02*
X219267Y105317D01*
X219017Y105108D01*
X218850Y104858D01*
X218725Y104525D01*
X218683Y104150D01*
X218725Y103775D01*
X218850Y103442D01*
X219017Y103192D01*
X219267Y102983D01*
X219600Y102900D01*
X219933Y102983D01*
X220183Y103192D01*
X220350Y103442D01*
X220475Y103775D01*
X220517Y104150D01*
X220475Y104525D01*
X220350Y104858D01*
X220183Y105108D01*
X219933Y105317D01*
X219600Y105400D01*
G01X190408Y187817D02*
X190283Y187567D01*
X190200Y187275D01*
Y186942D01*
X190325Y186567D01*
X190533Y186275D01*
X190783Y186067D01*
X191200Y185900D01*
X191575Y185858D01*
X191950Y185942D01*
X192200Y186067D01*
X192450Y186317D01*
X192617Y186608D01*
X192700Y186900D01*
Y187192D01*
X192617Y187483D01*
X192492Y187733D01*
X192325Y187942D01*
G01Y189083D02*
X192533Y189333D01*
X192658Y189625D01*
X192700Y190000D01*
X192617Y190375D01*
X192450Y190667D01*
X192158Y190875D01*
X191825Y190917D01*
X191492Y190833D01*
X191283Y190625D01*
X191117Y190333D01*
X191075Y190042D01*
X191117Y189750D01*
X191283Y189375D01*
X190200Y189500D01*
Y190625D01*
G01X192408Y192392D02*
X192617Y192683D01*
X192700Y193017D01*
X192617Y193350D01*
X192367Y193642D01*
X191992Y193850D01*
X191617Y193933D01*
X191158D01*
X190783Y193850D01*
X190450Y193642D01*
X190283Y193392D01*
X190200Y193100D01*
X190283Y192767D01*
X190450Y192517D01*
X190700Y192350D01*
X191033Y192267D01*
X191325Y192350D01*
X191617Y192558D01*
X191783Y192808D01*
X191825Y193100D01*
X191742Y193433D01*
X191533Y193683D01*
X191158Y193933D01*
G01X215217Y189700D02*
Y192200D01*
X216258D01*
X216592Y192075D01*
X216800Y191908D01*
X216883Y191575D01*
X216800Y191242D01*
X216550Y191033D01*
X216258Y190908D01*
X215217D01*
G01X216258D02*
X216883Y189700D01*
G01X219150D02*
Y192200D01*
X218650Y191700D01*
G01Y189700D02*
X219650D01*
G01X222250Y192200D02*
X221917Y192117D01*
X221667Y191908D01*
X221500Y191658D01*
X221375Y191325D01*
X221333Y190950D01*
X221375Y190575D01*
X221500Y190242D01*
X221667Y189992D01*
X221917Y189783D01*
X222250Y189700D01*
X222583Y189783D01*
X222833Y189992D01*
X223000Y190242D01*
X223125Y190575D01*
X223167Y190950D01*
X223125Y191325D01*
X223000Y191658D01*
X222833Y191908D01*
X222583Y192117D01*
X222250Y192200D01*
G01X224558Y190742D02*
X224850Y191033D01*
X225100Y191200D01*
X225433Y191283D01*
X225725Y191200D01*
X225933Y191033D01*
X226100Y190783D01*
X226142Y190492D01*
X226100Y190242D01*
X225933Y189992D01*
X225683Y189783D01*
X225392Y189700D01*
X225058Y189783D01*
X224767Y190033D01*
X224600Y190408D01*
X224558Y190825D01*
X224642Y191367D01*
X224767Y191658D01*
X224975Y191950D01*
X225267Y192158D01*
X225558Y192200D01*
X225850Y192117D01*
X226058Y191908D01*
G01X232034Y193198D02*
Y197198D01*
X224634D01*
G01X230967Y187200D02*
Y189700D01*
X232008D01*
X232342Y189575D01*
X232550Y189408D01*
X232633Y189075D01*
X232550Y188742D01*
X232300Y188533D01*
X232008Y188408D01*
X230967D01*
G01X232008D02*
X232633Y187200D01*
G01X233983Y187700D02*
X234233Y187408D01*
X234567Y187242D01*
X234942Y187200D01*
X235275Y187242D01*
X235608Y187450D01*
X235817Y187700D01*
X235858Y187950D01*
X235775Y188242D01*
X235483Y188450D01*
X235192Y188533D01*
X234817D01*
G01X235192D02*
X235442Y188658D01*
X235650Y188867D01*
X235733Y189117D01*
X235650Y189367D01*
X235442Y189575D01*
X235067Y189700D01*
X234692Y189658D01*
X234317Y189492D01*
G01X238000Y187200D02*
X238292Y187242D01*
X238625Y187367D01*
X238833Y187575D01*
X238917Y187867D01*
X238833Y188158D01*
X238583Y188408D01*
X238208Y188533D01*
X237792D01*
X237542Y188617D01*
X237333Y188825D01*
X237250Y189117D01*
X237375Y189408D01*
X237667Y189617D01*
X238000Y189700D01*
X238333Y189617D01*
X238625Y189408D01*
X238750Y189117D01*
X238667Y188825D01*
X238458Y188617D01*
X238208Y188533D01*
X237792D01*
X237417Y188408D01*
X237167Y188158D01*
X237083Y187867D01*
X237167Y187575D01*
X237375Y187367D01*
X237708Y187242D01*
X238000Y187200D01*
G01X241200Y195200D02*
Y191200D01*
X248600D01*
G01X254400Y192167D02*
X251900D01*
Y193208D01*
X252025Y193542D01*
X252192Y193750D01*
X252525Y193833D01*
X252858Y193750D01*
X253067Y193500D01*
X253192Y193208D01*
Y192167D01*
G01Y193208D02*
X254400Y193833D01*
G01X253900Y195183D02*
X254192Y195433D01*
X254358Y195767D01*
X254400Y196142D01*
X254358Y196475D01*
X254150Y196808D01*
X253900Y197017D01*
X253650Y197058D01*
X253358Y196975D01*
X253150Y196683D01*
X253067Y196392D01*
Y196017D01*
G01Y196392D02*
X252942Y196642D01*
X252733Y196850D01*
X252483Y196933D01*
X252233Y196850D01*
X252025Y196642D01*
X251900Y196267D01*
X251942Y195892D01*
X252108Y195517D01*
G01X254108Y198492D02*
X254317Y198783D01*
X254400Y199117D01*
X254317Y199450D01*
X254067Y199742D01*
X253692Y199950D01*
X253317Y200033D01*
X252858D01*
X252483Y199950D01*
X252150Y199742D01*
X251983Y199492D01*
X251900Y199200D01*
X251983Y198867D01*
X252150Y198617D01*
X252400Y198450D01*
X252733Y198367D01*
X253025Y198450D01*
X253317Y198658D01*
X253483Y198908D01*
X253525Y199200D01*
X253442Y199533D01*
X253233Y199783D01*
X252858Y200033D01*
G01X248598Y195300D02*
Y199300D01*
X241198D01*
G01X216067Y185200D02*
Y187700D01*
X217108D01*
X217442Y187575D01*
X217650Y187408D01*
X217733Y187075D01*
X217650Y186742D01*
X217400Y186533D01*
X217108Y186408D01*
X216067D01*
G01X217108D02*
X217733Y185200D01*
G01X219917D02*
X220000Y185742D01*
X220125Y186200D01*
X220292Y186617D01*
X220500Y187075D01*
X220833Y187700D01*
X219167D01*
G01X222308Y187283D02*
X222558Y187533D01*
X222850Y187658D01*
X223183Y187700D01*
X223600Y187617D01*
X223892Y187408D01*
X223975Y187158D01*
X223933Y186908D01*
X223767Y186700D01*
X222933Y186283D01*
X222558Y185992D01*
X222308Y185575D01*
X222225Y185200D01*
X223975D01*
G01X239600Y192400D02*
Y196400D01*
X232200D01*
G01X195067Y196000D02*
Y198500D01*
X196108D01*
X196442Y198375D01*
X196650Y198208D01*
X196733Y197875D01*
X196650Y197542D01*
X196400Y197333D01*
X196108Y197208D01*
X195067D01*
G01X196108D02*
X196733Y196000D01*
G01X198292Y196292D02*
X198583Y196083D01*
X198917Y196000D01*
X199250Y196083D01*
X199542Y196333D01*
X199750Y196708D01*
X199833Y197083D01*
Y197542D01*
X199750Y197917D01*
X199542Y198250D01*
X199292Y198417D01*
X199000Y198500D01*
X198667Y198417D01*
X198417Y198250D01*
X198250Y198000D01*
X198167Y197667D01*
X198250Y197375D01*
X198458Y197083D01*
X198708Y196917D01*
X199000Y196875D01*
X199333Y196958D01*
X199583Y197167D01*
X199833Y197542D01*
G01X201183Y196375D02*
X201433Y196167D01*
X201725Y196042D01*
X202100Y196000D01*
X202475Y196083D01*
X202767Y196250D01*
X202975Y196542D01*
X203017Y196875D01*
X202933Y197208D01*
X202725Y197417D01*
X202433Y197583D01*
X202142Y197625D01*
X201850Y197583D01*
X201475Y197417D01*
X201600Y198500D01*
X202725D01*
G01X205100Y197800D02*
Y193800D01*
X212500D01*
G01X230867Y183300D02*
Y185800D01*
X231908D01*
X232242Y185675D01*
X232450Y185508D01*
X232533Y185175D01*
X232450Y184842D01*
X232200Y184633D01*
X231908Y184508D01*
X230867D01*
G01X231908D02*
X232533Y183300D01*
G01X233883Y183675D02*
X234133Y183467D01*
X234425Y183342D01*
X234800Y183300D01*
X235175Y183383D01*
X235467Y183550D01*
X235675Y183842D01*
X235717Y184175D01*
X235633Y184508D01*
X235425Y184717D01*
X235133Y184883D01*
X234842Y184925D01*
X234550Y184883D01*
X234175Y184717D01*
X234300Y185800D01*
X235425D01*
G01X236983Y183800D02*
X237233Y183508D01*
X237567Y183342D01*
X237942Y183300D01*
X238275Y183342D01*
X238608Y183550D01*
X238817Y183800D01*
X238858Y184050D01*
X238775Y184342D01*
X238483Y184550D01*
X238192Y184633D01*
X237817D01*
G01X238192D02*
X238442Y184758D01*
X238650Y184967D01*
X238733Y185217D01*
X238650Y185467D01*
X238442Y185675D01*
X238067Y185800D01*
X237692Y185758D01*
X237317Y185592D01*
G01X241200Y191000D02*
Y187000D01*
X248600D01*
G01X251800Y182900D02*
Y186900D01*
X244400D01*
G01X215367Y196200D02*
Y198700D01*
X216408D01*
X216742Y198575D01*
X216950Y198408D01*
X217033Y198075D01*
X216950Y197742D01*
X216700Y197533D01*
X216408Y197408D01*
X215367D01*
G01X216408D02*
X217033Y196200D01*
G01X218508Y198283D02*
X218758Y198533D01*
X219050Y198658D01*
X219383Y198700D01*
X219800Y198617D01*
X220092Y198408D01*
X220175Y198158D01*
X220133Y197908D01*
X219967Y197700D01*
X219133Y197283D01*
X218758Y196992D01*
X218508Y196575D01*
X218425Y196200D01*
X220175D01*
G01X222317D02*
X222400Y196742D01*
X222525Y197200D01*
X222692Y197617D01*
X222900Y198075D01*
X223233Y198700D01*
X221567D01*
G01X232200Y200500D02*
Y196500D01*
X239600D01*
G01X325000Y21700D02*
Y17700D01*
X332400D01*
G01X345538Y2469D02*
Y33169D01*
G01X359538Y2469D02*
X345538D01*
G01X316050Y54900D02*
Y52400D01*
G01X315092Y54900D02*
X317008D01*
G01X318317Y52400D02*
Y54900D01*
X319317D01*
X319650Y54775D01*
X319900Y54483D01*
X319983Y54150D01*
X319900Y53817D01*
X319692Y53567D01*
X319317Y53442D01*
X318317D01*
G01X322750Y52400D02*
Y54900D01*
X321208Y53108D01*
X323292D01*
G01X324558Y53442D02*
X324850Y53733D01*
X325100Y53900D01*
X325433Y53983D01*
X325725Y53900D01*
X325933Y53733D01*
X326100Y53483D01*
X326142Y53192D01*
X326100Y52942D01*
X325933Y52692D01*
X325683Y52483D01*
X325392Y52400D01*
X325058Y52483D01*
X324767Y52733D01*
X324600Y53108D01*
X324558Y53525D01*
X324642Y54067D01*
X324767Y54358D01*
X324975Y54650D01*
X325267Y54858D01*
X325558Y54900D01*
X325850Y54817D01*
X326058Y54608D01*
G01X316050Y63200D02*
Y60700D01*
G01X315092Y63200D02*
X317008D01*
G01X318317Y60700D02*
Y63200D01*
X319317D01*
X319650Y63075D01*
X319900Y62783D01*
X319983Y62450D01*
X319900Y62117D01*
X319692Y61867D01*
X319317Y61742D01*
X318317D01*
G01X322750Y60700D02*
Y63200D01*
X321208Y61408D01*
X323292D01*
G01X325850Y60700D02*
Y63200D01*
X324308Y61408D01*
X326392D01*
G01X315900Y75750D02*
X318400D01*
G01X315900Y74792D02*
Y76708D01*
G01X318400Y78017D02*
X315900D01*
Y79017D01*
X316025Y79350D01*
X316317Y79600D01*
X316650Y79683D01*
X316983Y79600D01*
X317233Y79392D01*
X317358Y79017D01*
Y78017D01*
G01X318400Y82450D02*
X315900D01*
X317692Y80908D01*
Y82992D01*
G01X317900Y84133D02*
X318192Y84383D01*
X318358Y84717D01*
X318400Y85092D01*
X318358Y85425D01*
X318150Y85758D01*
X317900Y85967D01*
X317650Y86008D01*
X317358Y85925D01*
X317150Y85633D01*
X317067Y85342D01*
Y84967D01*
G01Y85342D02*
X316942Y85592D01*
X316733Y85800D01*
X316483Y85883D01*
X316233Y85800D01*
X316025Y85592D01*
X315900Y85217D01*
X315942Y84842D01*
X316108Y84467D01*
G01X316288Y58951D02*
Y56451D01*
G01X315330Y58951D02*
X317246D01*
G01X318555Y56451D02*
Y58951D01*
X319555D01*
X319888Y58826D01*
X320138Y58534D01*
X320221Y58201D01*
X320138Y57868D01*
X319930Y57618D01*
X319555Y57493D01*
X318555D01*
G01X322988Y56451D02*
Y58951D01*
X321446Y57159D01*
X323530D01*
G01X324671Y56826D02*
X324921Y56618D01*
X325213Y56493D01*
X325588Y56451D01*
X325963Y56534D01*
X326255Y56701D01*
X326463Y56993D01*
X326505Y57326D01*
X326421Y57659D01*
X326213Y57868D01*
X325921Y58034D01*
X325630Y58076D01*
X325338Y58034D01*
X324963Y57868D01*
X325088Y58951D01*
X326213D01*
G01X290203Y64176D02*
X289953Y64301D01*
X289661Y64384D01*
X289328D01*
X288953Y64259D01*
X288661Y64051D01*
X288453Y63801D01*
X288286Y63384D01*
X288244Y63009D01*
X288328Y62634D01*
X288453Y62384D01*
X288703Y62134D01*
X288994Y61967D01*
X289286Y61884D01*
X289578D01*
X289869Y61967D01*
X290119Y62092D01*
X290328Y62259D01*
G01X292886Y61884D02*
Y64384D01*
X291344Y62592D01*
X293428D01*
G01X295486Y61884D02*
Y64384D01*
X294986Y63884D01*
G01Y61884D02*
X295986D01*
G01X317217Y70992D02*
X316967Y71117D01*
X316675Y71200D01*
X316342D01*
X315967Y71075D01*
X315675Y70867D01*
X315467Y70617D01*
X315300Y70200D01*
X315258Y69825D01*
X315342Y69450D01*
X315467Y69200D01*
X315717Y68950D01*
X316008Y68783D01*
X316300Y68700D01*
X316592D01*
X316883Y68783D01*
X317133Y68908D01*
X317342Y69075D01*
G01X318483Y71200D02*
Y69408D01*
X318650Y69033D01*
X318983Y68783D01*
X319400Y68700D01*
X319817Y68783D01*
X320150Y69033D01*
X320317Y69408D01*
Y71200D01*
G01X321792Y68992D02*
X322083Y68783D01*
X322417Y68700D01*
X322750Y68783D01*
X323042Y69033D01*
X323250Y69408D01*
X323333Y69783D01*
Y70242D01*
X323250Y70617D01*
X323042Y70950D01*
X322792Y71117D01*
X322500Y71200D01*
X322167Y71117D01*
X321917Y70950D01*
X321750Y70700D01*
X321667Y70367D01*
X321750Y70075D01*
X321958Y69783D01*
X322208Y69617D01*
X322500Y69575D01*
X322833Y69658D01*
X323083Y69867D01*
X323333Y70242D01*
G01X317178Y67161D02*
X316928Y67286D01*
X316636Y67369D01*
X316303D01*
X315928Y67244D01*
X315636Y67036D01*
X315428Y66786D01*
X315261Y66369D01*
X315219Y65994D01*
X315303Y65619D01*
X315428Y65369D01*
X315678Y65119D01*
X315969Y64952D01*
X316261Y64869D01*
X316553D01*
X316844Y64952D01*
X317094Y65077D01*
X317303Y65244D01*
G01X318444Y67369D02*
Y65577D01*
X318611Y65202D01*
X318944Y64952D01*
X319361Y64869D01*
X319778Y64952D01*
X320111Y65202D01*
X320278Y65577D01*
Y67369D01*
G01X322961Y64869D02*
Y67369D01*
X321419Y65577D01*
X323503D01*
G01X320608Y84117D02*
X320483Y83867D01*
X320400Y83575D01*
Y83242D01*
X320525Y82867D01*
X320733Y82575D01*
X320983Y82367D01*
X321400Y82200D01*
X321775Y82158D01*
X322150Y82242D01*
X322400Y82367D01*
X322650Y82617D01*
X322817Y82908D01*
X322900Y83200D01*
Y83492D01*
X322817Y83783D01*
X322692Y84033D01*
X322525Y84242D01*
G01X320400Y85383D02*
X322192D01*
X322567Y85550D01*
X322817Y85883D01*
X322900Y86300D01*
X322817Y86717D01*
X322567Y87050D01*
X322192Y87217D01*
X320400D01*
G01X322400Y88483D02*
X322692Y88733D01*
X322858Y89067D01*
X322900Y89442D01*
X322858Y89775D01*
X322650Y90108D01*
X322400Y90317D01*
X322150Y90358D01*
X321858Y90275D01*
X321650Y89983D01*
X321567Y89692D01*
Y89317D01*
G01Y89692D02*
X321442Y89942D01*
X321233Y90150D01*
X320983Y90233D01*
X320733Y90150D01*
X320525Y89942D01*
X320400Y89567D01*
X320442Y89192D01*
X320608Y88817D01*
G01X290231Y99108D02*
X289981Y99233D01*
X289689Y99316D01*
X289356D01*
X288981Y99191D01*
X288689Y98983D01*
X288481Y98733D01*
X288314Y98316D01*
X288272Y97941D01*
X288356Y97566D01*
X288481Y97316D01*
X288731Y97066D01*
X289022Y96899D01*
X289314Y96816D01*
X289606D01*
X289897Y96899D01*
X290147Y97024D01*
X290356Y97191D01*
G01X292914Y96816D02*
Y99316D01*
X291372Y97524D01*
X293456D01*
G01X294722Y98899D02*
X294972Y99149D01*
X295264Y99274D01*
X295597Y99316D01*
X296014Y99233D01*
X296306Y99024D01*
X296389Y98774D01*
X296347Y98524D01*
X296181Y98316D01*
X295347Y97899D01*
X294972Y97608D01*
X294722Y97191D01*
X294639Y96816D01*
X296389D01*
G01X321308Y25867D02*
X321183Y25617D01*
X321100Y25325D01*
Y24992D01*
X321225Y24617D01*
X321433Y24325D01*
X321683Y24117D01*
X322100Y23950D01*
X322475Y23908D01*
X322850Y23992D01*
X323100Y24117D01*
X323350Y24367D01*
X323517Y24658D01*
X323600Y24950D01*
Y25242D01*
X323517Y25533D01*
X323392Y25783D01*
X323225Y25992D01*
G01X321100Y27133D02*
X322892D01*
X323267Y27300D01*
X323517Y27633D01*
X323600Y28050D01*
X323517Y28467D01*
X323267Y28800D01*
X322892Y28967D01*
X321100D01*
G01X322558Y30358D02*
X322267Y30650D01*
X322100Y30900D01*
X322017Y31233D01*
X322100Y31525D01*
X322267Y31733D01*
X322517Y31900D01*
X322808Y31942D01*
X323058Y31900D01*
X323308Y31733D01*
X323517Y31483D01*
X323600Y31192D01*
X323517Y30858D01*
X323267Y30567D01*
X322892Y30400D01*
X322475Y30358D01*
X321933Y30442D01*
X321642Y30567D01*
X321350Y30775D01*
X321142Y31067D01*
X321100Y31358D01*
X321183Y31650D01*
X321392Y31858D01*
G01X323600Y34250D02*
X321100D01*
X321600Y33750D01*
G01X323600D02*
Y34750D01*
G01X286379Y50867D02*
Y53367D01*
X287420D01*
X287754Y53242D01*
X287962Y53075D01*
X288045Y52742D01*
X287962Y52409D01*
X287712Y52200D01*
X287420Y52075D01*
X286379D01*
G01X287420D02*
X288045Y50867D01*
G01X290312D02*
Y53367D01*
X289812Y52867D01*
G01Y50867D02*
X290812D01*
G01X293412D02*
Y53367D01*
X292912Y52867D01*
G01Y50867D02*
X293912D01*
G01X296512Y53367D02*
X296179Y53284D01*
X295929Y53075D01*
X295762Y52825D01*
X295637Y52492D01*
X295595Y52117D01*
X295637Y51742D01*
X295762Y51409D01*
X295929Y51159D01*
X296179Y50950D01*
X296512Y50867D01*
X296845Y50950D01*
X297095Y51159D01*
X297262Y51409D01*
X297387Y51742D01*
X297429Y52117D01*
X297387Y52492D01*
X297262Y52825D01*
X297095Y53075D01*
X296845Y53284D01*
X296512Y53367D01*
G01X268316Y34238D02*
Y36738D01*
X269357D01*
X269691Y36613D01*
X269899Y36446D01*
X269982Y36113D01*
X269899Y35780D01*
X269649Y35571D01*
X269357Y35446D01*
X268316D01*
G01X269357D02*
X269982Y34238D01*
G01X272249D02*
Y36738D01*
X271749Y36238D01*
G01Y34238D02*
X272749D01*
G01X275349D02*
Y36738D01*
X274849Y36238D01*
G01Y34238D02*
X275849D01*
G01X278449D02*
Y36738D01*
X277949Y36238D01*
G01Y34238D02*
X278949D01*
G01X332400Y21900D02*
Y25900D01*
X325000D01*
G01X271606Y43425D02*
X269106D01*
Y44466D01*
X269231Y44800D01*
X269398Y45008D01*
X269731Y45091D01*
X270064Y45008D01*
X270273Y44758D01*
X270398Y44466D01*
Y43425D01*
G01Y44466D02*
X271606Y45091D01*
G01Y47358D02*
X269106D01*
X269606Y46858D01*
G01X271606D02*
Y47858D01*
G01Y50458D02*
X269106D01*
X269606Y49958D01*
G01X271606D02*
Y50958D01*
G01X269523Y52766D02*
X269273Y53016D01*
X269148Y53308D01*
X269106Y53641D01*
X269189Y54058D01*
X269398Y54350D01*
X269648Y54433D01*
X269898Y54391D01*
X270106Y54225D01*
X270523Y53391D01*
X270814Y53016D01*
X271231Y52766D01*
X271606Y52683D01*
Y54433D01*
G01X329800Y41300D02*
X325800D01*
Y33900D01*
G01X283183Y28149D02*
X280683D01*
Y29190D01*
X280808Y29524D01*
X280975Y29732D01*
X281308Y29815D01*
X281641Y29732D01*
X281850Y29482D01*
X281975Y29190D01*
Y28149D01*
G01Y29190D02*
X283183Y29815D01*
G01Y32082D02*
X280683D01*
X281183Y31582D01*
G01X283183D02*
Y32582D01*
G01Y35182D02*
X280683D01*
X281183Y34682D01*
G01X283183D02*
Y35682D01*
G01X282683Y37365D02*
X282975Y37615D01*
X283141Y37949D01*
X283183Y38324D01*
X283141Y38657D01*
X282933Y38990D01*
X282683Y39199D01*
X282433Y39240D01*
X282141Y39157D01*
X281933Y38865D01*
X281850Y38574D01*
Y38199D01*
G01Y38574D02*
X281725Y38824D01*
X281516Y39032D01*
X281266Y39115D01*
X281016Y39032D01*
X280808Y38824D01*
X280683Y38449D01*
X280725Y38074D01*
X280891Y37699D01*
G01X333500Y33600D02*
X329500D01*
Y26200D01*
G01X287356Y46655D02*
Y49155D01*
X288397D01*
X288731Y49030D01*
X288939Y48863D01*
X289022Y48530D01*
X288939Y48197D01*
X288689Y47988D01*
X288397Y47863D01*
X287356D01*
G01X288397D02*
X289022Y46655D01*
G01X291289D02*
Y49155D01*
X290789Y48655D01*
G01Y46655D02*
X291789D01*
G01X294389D02*
Y49155D01*
X293889Y48655D01*
G01Y46655D02*
X294889D01*
G01X297989D02*
Y49155D01*
X296447Y47363D01*
X298531D01*
G01X268459Y29490D02*
Y31990D01*
X269500D01*
X269834Y31865D01*
X270042Y31698D01*
X270125Y31365D01*
X270042Y31032D01*
X269792Y30823D01*
X269500Y30698D01*
X268459D01*
G01X269500D02*
X270125Y29490D01*
G01X272392D02*
Y31990D01*
X271892Y31490D01*
G01Y29490D02*
X272892D01*
G01X275492D02*
Y31990D01*
X274992Y31490D01*
G01Y29490D02*
X275992D01*
G01X278509D02*
X278592Y30032D01*
X278717Y30490D01*
X278884Y30907D01*
X279092Y31365D01*
X279425Y31990D01*
X277759D01*
G01X288017Y93000D02*
Y95500D01*
X289058D01*
X289392Y95375D01*
X289600Y95208D01*
X289683Y94875D01*
X289600Y94542D01*
X289350Y94333D01*
X289058Y94208D01*
X288017D01*
G01X289058D02*
X289683Y93000D01*
G01X291950D02*
Y95500D01*
X291450Y95000D01*
G01Y93000D02*
X292450D01*
G01X295050D02*
Y95500D01*
X294550Y95000D01*
G01Y93000D02*
X295550D01*
G01X297358Y94042D02*
X297650Y94333D01*
X297900Y94500D01*
X298233Y94583D01*
X298525Y94500D01*
X298733Y94333D01*
X298900Y94083D01*
X298942Y93792D01*
X298900Y93542D01*
X298733Y93292D01*
X298483Y93083D01*
X298192Y93000D01*
X297858Y93083D01*
X297567Y93333D01*
X297400Y93708D01*
X297358Y94125D01*
X297442Y94667D01*
X297567Y94958D01*
X297775Y95250D01*
X298067Y95458D01*
X298358Y95500D01*
X298650Y95417D01*
X298858Y95208D01*
G01X291336Y22983D02*
Y25483D01*
X292377D01*
X292711Y25358D01*
X292919Y25191D01*
X293002Y24858D01*
X292919Y24525D01*
X292669Y24316D01*
X292377Y24191D01*
X291336D01*
G01X292377D02*
X293002Y22983D01*
G01X295269D02*
Y25483D01*
X294769Y24983D01*
G01Y22983D02*
X295769D01*
G01X298369D02*
Y25483D01*
X297869Y24983D01*
G01Y22983D02*
X298869D01*
G01X301469D02*
X301761Y23025D01*
X302094Y23150D01*
X302302Y23358D01*
X302386Y23650D01*
X302302Y23941D01*
X302052Y24191D01*
X301677Y24316D01*
X301261D01*
X301011Y24400D01*
X300802Y24608D01*
X300719Y24900D01*
X300844Y25191D01*
X301136Y25400D01*
X301469Y25483D01*
X301802Y25400D01*
X302094Y25191D01*
X302219Y24900D01*
X302136Y24608D01*
X301927Y24400D01*
X301677Y24316D01*
X301261D01*
X300886Y24191D01*
X300636Y23941D01*
X300552Y23650D01*
X300636Y23358D01*
X300844Y23150D01*
X301177Y23025D01*
X301469Y22983D01*
G01X275814Y43707D02*
X273314D01*
Y44748D01*
X273439Y45082D01*
X273606Y45290D01*
X273939Y45373D01*
X274272Y45290D01*
X274481Y45040D01*
X274606Y44748D01*
Y43707D01*
G01Y44748D02*
X275814Y45373D01*
G01Y48140D02*
X273314D01*
X275106Y46598D01*
Y48682D01*
G01X275814Y51240D02*
X273314D01*
X275106Y49698D01*
Y51782D01*
G01X334100Y41400D02*
X330100D01*
Y34000D01*
G01X268317Y67000D02*
Y69500D01*
X269358D01*
X269692Y69375D01*
X269900Y69208D01*
X269983Y68875D01*
X269900Y68542D01*
X269650Y68333D01*
X269358Y68208D01*
X268317D01*
G01X269358D02*
X269983Y67000D01*
G01X272250D02*
Y69500D01*
X271750Y69000D01*
G01Y67000D02*
X272750D01*
G01X275350D02*
Y69500D01*
X274850Y69000D01*
G01Y67000D02*
X275850D01*
G01X277533Y67375D02*
X277783Y67167D01*
X278075Y67042D01*
X278450Y67000D01*
X278825Y67083D01*
X279117Y67250D01*
X279325Y67542D01*
X279367Y67875D01*
X279283Y68208D01*
X279075Y68417D01*
X278783Y68583D01*
X278492Y68625D01*
X278200Y68583D01*
X277825Y68417D01*
X277950Y69500D01*
X279075D01*
G01X338200Y54300D02*
Y58300D01*
X330800D01*
G01X268417Y62500D02*
Y65000D01*
X269458D01*
X269792Y64875D01*
X270000Y64708D01*
X270083Y64375D01*
X270000Y64042D01*
X269750Y63833D01*
X269458Y63708D01*
X268417D01*
G01X269458D02*
X270083Y62500D01*
G01X272350D02*
Y65000D01*
X271850Y64500D01*
G01Y62500D02*
X272850D01*
G01X275950D02*
Y65000D01*
X274408Y63208D01*
X276492D01*
G01X277633Y62875D02*
X277883Y62667D01*
X278175Y62542D01*
X278550Y62500D01*
X278925Y62583D01*
X279217Y62750D01*
X279425Y63042D01*
X279467Y63375D01*
X279383Y63708D01*
X279175Y63917D01*
X278883Y64083D01*
X278592Y64125D01*
X278300Y64083D01*
X277925Y63917D01*
X278050Y65000D01*
X279175D01*
G01X330800Y54200D02*
Y50200D01*
X338200D01*
G01X301715Y69660D02*
Y72160D01*
X302756D01*
X303090Y72035D01*
X303298Y71868D01*
X303381Y71535D01*
X303298Y71202D01*
X303048Y70993D01*
X302756Y70868D01*
X301715D01*
G01X302756D02*
X303381Y69660D01*
G01X305648D02*
Y72160D01*
X305148Y71660D01*
G01Y69660D02*
X306148D01*
G01X309248D02*
Y72160D01*
X307706Y70368D01*
X309790D01*
G01X311848Y69660D02*
Y72160D01*
X311348Y71660D01*
G01Y69660D02*
X312348D01*
G01X291567Y58200D02*
Y60700D01*
X292608D01*
X292942Y60575D01*
X293150Y60408D01*
X293233Y60075D01*
X293150Y59742D01*
X292900Y59533D01*
X292608Y59408D01*
X291567D01*
G01X292608D02*
X293233Y58200D01*
G01X296000D02*
Y60700D01*
X294458Y58908D01*
X296542D01*
G01X297683Y58575D02*
X297933Y58367D01*
X298225Y58242D01*
X298600Y58200D01*
X298975Y58283D01*
X299267Y58450D01*
X299475Y58742D01*
X299517Y59075D01*
X299433Y59408D01*
X299225Y59617D01*
X298933Y59783D01*
X298642Y59825D01*
X298350Y59783D01*
X297975Y59617D01*
X298100Y60700D01*
X299225D01*
G01X291667Y54600D02*
Y57100D01*
X292708D01*
X293042Y56975D01*
X293250Y56808D01*
X293333Y56475D01*
X293250Y56142D01*
X293000Y55933D01*
X292708Y55808D01*
X291667D01*
G01X292708D02*
X293333Y54600D01*
G01X296100D02*
Y57100D01*
X294558Y55308D01*
X296642D01*
G01X298700Y54600D02*
Y57100D01*
X298200Y56600D01*
G01Y54600D02*
X299200D01*
G01X318939Y23617D02*
X316439D01*
Y24658D01*
X316564Y24992D01*
X316731Y25200D01*
X317064Y25283D01*
X317397Y25200D01*
X317606Y24950D01*
X317731Y24658D01*
Y23617D01*
G01Y24658D02*
X318939Y25283D01*
G01X316439Y26633D02*
X318231D01*
X318606Y26800D01*
X318856Y27133D01*
X318939Y27550D01*
X318856Y27967D01*
X318606Y28300D01*
X318231Y28467D01*
X316439D01*
G01X318647Y29942D02*
X318856Y30233D01*
X318939Y30567D01*
X318856Y30900D01*
X318606Y31192D01*
X318231Y31400D01*
X317856Y31483D01*
X317397D01*
X317022Y31400D01*
X316689Y31192D01*
X316522Y30942D01*
X316439Y30650D01*
X316522Y30317D01*
X316689Y30067D01*
X316939Y29900D01*
X317272Y29817D01*
X317564Y29900D01*
X317856Y30108D01*
X318022Y30358D01*
X318064Y30650D01*
X317981Y30983D01*
X317772Y31233D01*
X317397Y31483D01*
G01X317897Y32958D02*
X317606Y33250D01*
X317439Y33500D01*
X317356Y33833D01*
X317439Y34125D01*
X317606Y34333D01*
X317856Y34500D01*
X318147Y34542D01*
X318397Y34500D01*
X318647Y34333D01*
X318856Y34083D01*
X318939Y33792D01*
X318856Y33458D01*
X318606Y33167D01*
X318231Y33000D01*
X317814Y32958D01*
X317272Y33042D01*
X316981Y33167D01*
X316689Y33375D01*
X316481Y33667D01*
X316439Y33958D01*
X316522Y34250D01*
X316731Y34458D01*
G01X301517Y77200D02*
Y79700D01*
X302558D01*
X302892Y79575D01*
X303100Y79408D01*
X303183Y79075D01*
X303100Y78742D01*
X302850Y78533D01*
X302558Y78408D01*
X301517D01*
G01X302558D02*
X303183Y77200D01*
G01X305450D02*
Y79700D01*
X304950Y79200D01*
G01Y77200D02*
X305950D01*
G01X309050D02*
Y79700D01*
X307508Y77908D01*
X309592D01*
G01X311567Y77200D02*
X311650Y77742D01*
X311775Y78200D01*
X311942Y78617D01*
X312150Y79075D01*
X312483Y79700D01*
X310817D01*
G01X301817Y81000D02*
Y83500D01*
X302858D01*
X303192Y83375D01*
X303400Y83208D01*
X303483Y82875D01*
X303400Y82542D01*
X303150Y82333D01*
X302858Y82208D01*
X301817D01*
G01X302858D02*
X303483Y81000D01*
G01X305750D02*
Y83500D01*
X305250Y83000D01*
G01Y81000D02*
X306250D01*
G01X309350D02*
Y83500D01*
X307808Y81708D01*
X309892D01*
G01X311158Y82042D02*
X311450Y82333D01*
X311700Y82500D01*
X312033Y82583D01*
X312325Y82500D01*
X312533Y82333D01*
X312700Y82083D01*
X312742Y81792D01*
X312700Y81542D01*
X312533Y81292D01*
X312283Y81083D01*
X311992Y81000D01*
X311658Y81083D01*
X311367Y81333D01*
X311200Y81708D01*
X311158Y82125D01*
X311242Y82667D01*
X311367Y82958D01*
X311575Y83250D01*
X311867Y83458D01*
X312158Y83500D01*
X312450Y83417D01*
X312658Y83208D01*
G01X301519Y73410D02*
Y75910D01*
X302560D01*
X302894Y75785D01*
X303102Y75618D01*
X303185Y75285D01*
X303102Y74952D01*
X302852Y74743D01*
X302560Y74618D01*
X301519D01*
G01X302560D02*
X303185Y73410D01*
G01X305452D02*
Y75910D01*
X304952Y75410D01*
G01Y73410D02*
X305952D01*
G01X309052D02*
Y75910D01*
X307510Y74118D01*
X309594D01*
G01X311652Y75910D02*
X311319Y75827D01*
X311069Y75618D01*
X310902Y75368D01*
X310777Y75035D01*
X310735Y74660D01*
X310777Y74285D01*
X310902Y73952D01*
X311069Y73702D01*
X311319Y73493D01*
X311652Y73410D01*
X311985Y73493D01*
X312235Y73702D01*
X312402Y73952D01*
X312527Y74285D01*
X312569Y74660D01*
X312527Y75035D01*
X312402Y75368D01*
X312235Y75618D01*
X311985Y75827D01*
X311652Y75910D01*
G01X288517Y89000D02*
Y91500D01*
X289558D01*
X289892Y91375D01*
X290100Y91208D01*
X290183Y90875D01*
X290100Y90542D01*
X289850Y90333D01*
X289558Y90208D01*
X288517D01*
G01X289558D02*
X290183Y89000D01*
G01X292450D02*
Y91500D01*
X291950Y91000D01*
G01Y89000D02*
X292950D01*
G01X296050D02*
Y91500D01*
X294508Y89708D01*
X296592D01*
G01X299150Y89000D02*
Y91500D01*
X297608Y89708D01*
X299692D01*
G01X268425Y75994D02*
Y78494D01*
X269466D01*
X269800Y78369D01*
X270008Y78202D01*
X270091Y77869D01*
X270008Y77536D01*
X269758Y77327D01*
X269466Y77202D01*
X268425D01*
G01X269466D02*
X270091Y75994D01*
G01X272358D02*
Y78494D01*
X271858Y77994D01*
G01Y75994D02*
X272858D01*
G01X275958D02*
Y78494D01*
X274416Y76702D01*
X276500D01*
G01X277641Y76494D02*
X277891Y76202D01*
X278225Y76036D01*
X278600Y75994D01*
X278933Y76036D01*
X279266Y76244D01*
X279475Y76494D01*
X279516Y76744D01*
X279433Y77036D01*
X279141Y77244D01*
X278850Y77327D01*
X278475D01*
G01X278850D02*
X279100Y77452D01*
X279308Y77661D01*
X279391Y77911D01*
X279308Y78161D01*
X279100Y78369D01*
X278725Y78494D01*
X278350Y78452D01*
X277975Y78286D01*
G01X328700Y66700D02*
Y62700D01*
X336100D01*
G01X268417Y71700D02*
Y74200D01*
X269458D01*
X269792Y74075D01*
X270000Y73908D01*
X270083Y73575D01*
X270000Y73242D01*
X269750Y73033D01*
X269458Y72908D01*
X268417D01*
G01X269458D02*
X270083Y71700D01*
G01X272350D02*
Y74200D01*
X271850Y73700D01*
G01Y71700D02*
X272850D01*
G01X275950D02*
Y74200D01*
X274408Y72408D01*
X276492D01*
G01X277758Y73783D02*
X278008Y74033D01*
X278300Y74158D01*
X278633Y74200D01*
X279050Y74117D01*
X279342Y73908D01*
X279425Y73658D01*
X279383Y73408D01*
X279217Y73200D01*
X278383Y72783D01*
X278008Y72492D01*
X277758Y72075D01*
X277675Y71700D01*
X279425D01*
G01X338200Y58400D02*
Y62400D01*
X330800D01*
G01X290615Y27540D02*
Y30040D01*
X291656D01*
X291990Y29915D01*
X292198Y29748D01*
X292281Y29415D01*
X292198Y29082D01*
X291948Y28873D01*
X291656Y28748D01*
X290615D01*
G01X291656D02*
X292281Y27540D01*
G01X294548D02*
Y30040D01*
X294048Y29540D01*
G01Y27540D02*
X295048D01*
G01X296856Y29623D02*
X297106Y29873D01*
X297398Y29998D01*
X297731Y30040D01*
X298148Y29957D01*
X298440Y29748D01*
X298523Y29498D01*
X298481Y29248D01*
X298315Y29040D01*
X297481Y28623D01*
X297106Y28332D01*
X296856Y27915D01*
X296773Y27540D01*
X298523D01*
G01X299956Y29623D02*
X300206Y29873D01*
X300498Y29998D01*
X300831Y30040D01*
X301248Y29957D01*
X301540Y29748D01*
X301623Y29498D01*
X301581Y29248D01*
X301415Y29040D01*
X300581Y28623D01*
X300206Y28332D01*
X299956Y27915D01*
X299873Y27540D01*
X301623D01*
G01X288128Y81488D02*
Y83988D01*
X289169D01*
X289503Y83863D01*
X289711Y83696D01*
X289794Y83363D01*
X289711Y83030D01*
X289461Y82821D01*
X289169Y82696D01*
X288128D01*
G01X289169D02*
X289794Y81488D01*
G01X292061D02*
Y83988D01*
X291561Y83488D01*
G01Y81488D02*
X292561D01*
G01X294244Y81988D02*
X294494Y81696D01*
X294828Y81530D01*
X295203Y81488D01*
X295536Y81530D01*
X295869Y81738D01*
X296078Y81988D01*
X296119Y82238D01*
X296036Y82530D01*
X295744Y82738D01*
X295453Y82821D01*
X295078D01*
G01X295453D02*
X295703Y82946D01*
X295911Y83155D01*
X295994Y83405D01*
X295911Y83655D01*
X295703Y83863D01*
X295328Y83988D01*
X294953Y83946D01*
X294578Y83780D01*
G01X297553Y81780D02*
X297844Y81571D01*
X298178Y81488D01*
X298511Y81571D01*
X298803Y81821D01*
X299011Y82196D01*
X299094Y82571D01*
Y83030D01*
X299011Y83405D01*
X298803Y83738D01*
X298553Y83905D01*
X298261Y83988D01*
X297928Y83905D01*
X297678Y83738D01*
X297511Y83488D01*
X297428Y83155D01*
X297511Y82863D01*
X297719Y82571D01*
X297969Y82405D01*
X298261Y82363D01*
X298594Y82446D01*
X298844Y82655D01*
X299094Y83030D01*
G01X288534Y85418D02*
Y87918D01*
X289575D01*
X289909Y87793D01*
X290117Y87626D01*
X290200Y87293D01*
X290117Y86960D01*
X289867Y86751D01*
X289575Y86626D01*
X288534D01*
G01X289575D02*
X290200Y85418D01*
G01X292467D02*
Y87918D01*
X291967Y87418D01*
G01Y85418D02*
X292967D01*
G01X294650Y85918D02*
X294900Y85626D01*
X295234Y85460D01*
X295609Y85418D01*
X295942Y85460D01*
X296275Y85668D01*
X296484Y85918D01*
X296525Y86168D01*
X296442Y86460D01*
X296150Y86668D01*
X295859Y86751D01*
X295484D01*
G01X295859D02*
X296109Y86876D01*
X296317Y87085D01*
X296400Y87335D01*
X296317Y87585D01*
X296109Y87793D01*
X295734Y87918D01*
X295359Y87876D01*
X294984Y87710D01*
G01X298667Y85418D02*
X298959Y85460D01*
X299292Y85585D01*
X299500Y85793D01*
X299584Y86085D01*
X299500Y86376D01*
X299250Y86626D01*
X298875Y86751D01*
X298459D01*
X298209Y86835D01*
X298000Y87043D01*
X297917Y87335D01*
X298042Y87626D01*
X298334Y87835D01*
X298667Y87918D01*
X299000Y87835D01*
X299292Y87626D01*
X299417Y87335D01*
X299334Y87043D01*
X299125Y86835D01*
X298875Y86751D01*
X298459D01*
X298084Y86626D01*
X297834Y86376D01*
X297750Y86085D01*
X297834Y85793D01*
X298042Y85585D01*
X298375Y85460D01*
X298667Y85418D01*
G01X301617Y65600D02*
Y68100D01*
X302658D01*
X302992Y67975D01*
X303200Y67808D01*
X303283Y67475D01*
X303200Y67142D01*
X302950Y66933D01*
X302658Y66808D01*
X301617D01*
G01X302658D02*
X303283Y65600D01*
G01X305550D02*
Y68100D01*
X305050Y67600D01*
G01Y65600D02*
X306050D01*
G01X307733Y66100D02*
X307983Y65808D01*
X308317Y65642D01*
X308692Y65600D01*
X309025Y65642D01*
X309358Y65850D01*
X309567Y66100D01*
X309608Y66350D01*
X309525Y66642D01*
X309233Y66850D01*
X308942Y66933D01*
X308567D01*
G01X308942D02*
X309192Y67058D01*
X309400Y67267D01*
X309483Y67517D01*
X309400Y67767D01*
X309192Y67975D01*
X308817Y68100D01*
X308442Y68058D01*
X308067Y67892D01*
G01X311667Y65600D02*
X311750Y66142D01*
X311875Y66600D01*
X312042Y67017D01*
X312250Y67475D01*
X312583Y68100D01*
X310917D01*
G01X301519Y61690D02*
Y64190D01*
X302560D01*
X302894Y64065D01*
X303102Y63898D01*
X303185Y63565D01*
X303102Y63232D01*
X302852Y63023D01*
X302560Y62898D01*
X301519D01*
G01X302560D02*
X303185Y61690D01*
G01X305452D02*
Y64190D01*
X304952Y63690D01*
G01Y61690D02*
X305952D01*
G01X307635Y62190D02*
X307885Y61898D01*
X308219Y61732D01*
X308594Y61690D01*
X308927Y61732D01*
X309260Y61940D01*
X309469Y62190D01*
X309510Y62440D01*
X309427Y62732D01*
X309135Y62940D01*
X308844Y63023D01*
X308469D01*
G01X308844D02*
X309094Y63148D01*
X309302Y63357D01*
X309385Y63607D01*
X309302Y63857D01*
X309094Y64065D01*
X308719Y64190D01*
X308344Y64148D01*
X307969Y63982D01*
G01X310860Y62732D02*
X311152Y63023D01*
X311402Y63190D01*
X311735Y63273D01*
X312027Y63190D01*
X312235Y63023D01*
X312402Y62773D01*
X312444Y62482D01*
X312402Y62232D01*
X312235Y61982D01*
X311985Y61773D01*
X311694Y61690D01*
X311360Y61773D01*
X311069Y62023D01*
X310902Y62398D01*
X310860Y62815D01*
X310944Y63357D01*
X311069Y63648D01*
X311277Y63940D01*
X311569Y64148D01*
X311860Y64190D01*
X312152Y64107D01*
X312360Y63898D01*
G01X287917Y77600D02*
Y80100D01*
X288958D01*
X289292Y79975D01*
X289500Y79808D01*
X289583Y79475D01*
X289500Y79142D01*
X289250Y78933D01*
X288958Y78808D01*
X287917D01*
G01X288958D02*
X289583Y77600D01*
G01X291850D02*
Y80100D01*
X291350Y79600D01*
G01Y77600D02*
X292350D01*
G01X294033Y78100D02*
X294283Y77808D01*
X294617Y77642D01*
X294992Y77600D01*
X295325Y77642D01*
X295658Y77850D01*
X295867Y78100D01*
X295908Y78350D01*
X295825Y78642D01*
X295533Y78850D01*
X295242Y78933D01*
X294867D01*
G01X295242D02*
X295492Y79058D01*
X295700Y79267D01*
X295783Y79517D01*
X295700Y79767D01*
X295492Y79975D01*
X295117Y80100D01*
X294742Y80058D01*
X294367Y79892D01*
G01X297133Y77975D02*
X297383Y77767D01*
X297675Y77642D01*
X298050Y77600D01*
X298425Y77683D01*
X298717Y77850D01*
X298925Y78142D01*
X298967Y78475D01*
X298883Y78808D01*
X298675Y79017D01*
X298383Y79183D01*
X298092Y79225D01*
X297800Y79183D01*
X297425Y79017D01*
X297550Y80100D01*
X298675D01*
G01X287817Y73700D02*
Y76200D01*
X288858D01*
X289192Y76075D01*
X289400Y75908D01*
X289483Y75575D01*
X289400Y75242D01*
X289150Y75033D01*
X288858Y74908D01*
X287817D01*
G01X288858D02*
X289483Y73700D01*
G01X291750D02*
Y76200D01*
X291250Y75700D01*
G01Y73700D02*
X292250D01*
G01X293933Y74200D02*
X294183Y73908D01*
X294517Y73742D01*
X294892Y73700D01*
X295225Y73742D01*
X295558Y73950D01*
X295767Y74200D01*
X295808Y74450D01*
X295725Y74742D01*
X295433Y74950D01*
X295142Y75033D01*
X294767D01*
G01X295142D02*
X295392Y75158D01*
X295600Y75367D01*
X295683Y75617D01*
X295600Y75867D01*
X295392Y76075D01*
X295017Y76200D01*
X294642Y76158D01*
X294267Y75992D01*
G01X298450Y73700D02*
Y76200D01*
X296908Y74408D01*
X298992D01*
G01X287617Y65700D02*
Y68200D01*
X288658D01*
X288992Y68075D01*
X289200Y67908D01*
X289283Y67575D01*
X289200Y67242D01*
X288950Y67033D01*
X288658Y66908D01*
X287617D01*
G01X288658D02*
X289283Y65700D01*
G01X291550D02*
Y68200D01*
X291050Y67700D01*
G01Y65700D02*
X292050D01*
G01X293733Y66200D02*
X293983Y65908D01*
X294317Y65742D01*
X294692Y65700D01*
X295025Y65742D01*
X295358Y65950D01*
X295567Y66200D01*
X295608Y66450D01*
X295525Y66742D01*
X295233Y66950D01*
X294942Y67033D01*
X294567D01*
G01X294942D02*
X295192Y67158D01*
X295400Y67367D01*
X295483Y67617D01*
X295400Y67867D01*
X295192Y68075D01*
X294817Y68200D01*
X294442Y68158D01*
X294067Y67992D01*
G01X296833Y66200D02*
X297083Y65908D01*
X297417Y65742D01*
X297792Y65700D01*
X298125Y65742D01*
X298458Y65950D01*
X298667Y66200D01*
X298708Y66450D01*
X298625Y66742D01*
X298333Y66950D01*
X298042Y67033D01*
X297667D01*
G01X298042D02*
X298292Y67158D01*
X298500Y67367D01*
X298583Y67617D01*
X298500Y67867D01*
X298292Y68075D01*
X297917Y68200D01*
X297542Y68158D01*
X297167Y67992D01*
G01X287817Y69600D02*
Y72100D01*
X288858D01*
X289192Y71975D01*
X289400Y71808D01*
X289483Y71475D01*
X289400Y71142D01*
X289150Y70933D01*
X288858Y70808D01*
X287817D01*
G01X288858D02*
X289483Y69600D01*
G01X291750D02*
Y72100D01*
X291250Y71600D01*
G01Y69600D02*
X292250D01*
G01X293933Y70100D02*
X294183Y69808D01*
X294517Y69642D01*
X294892Y69600D01*
X295225Y69642D01*
X295558Y69850D01*
X295767Y70100D01*
X295808Y70350D01*
X295725Y70642D01*
X295433Y70850D01*
X295142Y70933D01*
X294767D01*
G01X295142D02*
X295392Y71058D01*
X295600Y71267D01*
X295683Y71517D01*
X295600Y71767D01*
X295392Y71975D01*
X295017Y72100D01*
X294642Y72058D01*
X294267Y71892D01*
G01X297158Y71683D02*
X297408Y71933D01*
X297700Y72058D01*
X298033Y72100D01*
X298450Y72017D01*
X298742Y71808D01*
X298825Y71558D01*
X298783Y71308D01*
X298617Y71100D01*
X297783Y70683D01*
X297408Y70392D01*
X297158Y69975D01*
X297075Y69600D01*
X298825D01*
G01X300717Y46000D02*
Y48500D01*
X301758D01*
X302092Y48375D01*
X302300Y48208D01*
X302383Y47875D01*
X302300Y47542D01*
X302050Y47333D01*
X301758Y47208D01*
X300717D01*
G01X301758D02*
X302383Y46000D01*
G01X304650D02*
Y48500D01*
X304150Y48000D01*
G01Y46000D02*
X305150D01*
G01X306833Y46500D02*
X307083Y46208D01*
X307417Y46042D01*
X307792Y46000D01*
X308125Y46042D01*
X308458Y46250D01*
X308667Y46500D01*
X308708Y46750D01*
X308625Y47042D01*
X308333Y47250D01*
X308042Y47333D01*
X307667D01*
G01X308042D02*
X308292Y47458D01*
X308500Y47667D01*
X308583Y47917D01*
X308500Y48167D01*
X308292Y48375D01*
X307917Y48500D01*
X307542Y48458D01*
X307167Y48292D01*
G01X310850Y46000D02*
Y48500D01*
X310350Y48000D01*
G01Y46000D02*
X311350D01*
G01X300317Y51300D02*
Y53800D01*
X301358D01*
X301692Y53675D01*
X301900Y53508D01*
X301983Y53175D01*
X301900Y52842D01*
X301650Y52633D01*
X301358Y52508D01*
X300317D01*
G01X301358D02*
X301983Y51300D01*
G01X304250D02*
Y53800D01*
X303750Y53300D01*
G01Y51300D02*
X304750D01*
G01X306433Y51800D02*
X306683Y51508D01*
X307017Y51342D01*
X307392Y51300D01*
X307725Y51342D01*
X308058Y51550D01*
X308267Y51800D01*
X308308Y52050D01*
X308225Y52342D01*
X307933Y52550D01*
X307642Y52633D01*
X307267D01*
G01X307642D02*
X307892Y52758D01*
X308100Y52967D01*
X308183Y53217D01*
X308100Y53467D01*
X307892Y53675D01*
X307517Y53800D01*
X307142Y53758D01*
X306767Y53592D01*
G01X310450Y53800D02*
X310117Y53717D01*
X309867Y53508D01*
X309700Y53258D01*
X309575Y52925D01*
X309533Y52550D01*
X309575Y52175D01*
X309700Y51842D01*
X309867Y51592D01*
X310117Y51383D01*
X310450Y51300D01*
X310783Y51383D01*
X311033Y51592D01*
X311200Y51842D01*
X311325Y52175D01*
X311367Y52550D01*
X311325Y52925D01*
X311200Y53258D01*
X311033Y53508D01*
X310783Y53717D01*
X310450Y53800D01*
G01X286804Y41968D02*
Y44468D01*
X287845D01*
X288179Y44343D01*
X288387Y44176D01*
X288470Y43843D01*
X288387Y43510D01*
X288137Y43301D01*
X287845Y43176D01*
X286804D01*
G01X287845D02*
X288470Y41968D01*
G01X290737D02*
Y44468D01*
X290237Y43968D01*
G01Y41968D02*
X291237D01*
G01X293045Y44051D02*
X293295Y44301D01*
X293587Y44426D01*
X293920Y44468D01*
X294337Y44385D01*
X294629Y44176D01*
X294712Y43926D01*
X294670Y43676D01*
X294504Y43468D01*
X293670Y43051D01*
X293295Y42760D01*
X293045Y42343D01*
X292962Y41968D01*
X294712D01*
G01X296229Y42260D02*
X296520Y42051D01*
X296854Y41968D01*
X297187Y42051D01*
X297479Y42301D01*
X297687Y42676D01*
X297770Y43051D01*
Y43510D01*
X297687Y43885D01*
X297479Y44218D01*
X297229Y44385D01*
X296937Y44468D01*
X296604Y44385D01*
X296354Y44218D01*
X296187Y43968D01*
X296104Y43635D01*
X296187Y43343D01*
X296395Y43051D01*
X296645Y42885D01*
X296937Y42843D01*
X297270Y42926D01*
X297520Y43135D01*
X297770Y43510D01*
G01X287200Y36418D02*
Y38918D01*
X288241D01*
X288575Y38793D01*
X288783Y38626D01*
X288866Y38293D01*
X288783Y37960D01*
X288533Y37751D01*
X288241Y37626D01*
X287200D01*
G01X288241D02*
X288866Y36418D01*
G01X291133D02*
Y38918D01*
X290633Y38418D01*
G01Y36418D02*
X291633D01*
G01X293441Y38501D02*
X293691Y38751D01*
X293983Y38876D01*
X294316Y38918D01*
X294733Y38835D01*
X295025Y38626D01*
X295108Y38376D01*
X295066Y38126D01*
X294900Y37918D01*
X294066Y37501D01*
X293691Y37210D01*
X293441Y36793D01*
X293358Y36418D01*
X295108D01*
G01X297333D02*
X297625Y36460D01*
X297958Y36585D01*
X298166Y36793D01*
X298250Y37085D01*
X298166Y37376D01*
X297916Y37626D01*
X297541Y37751D01*
X297125D01*
X296875Y37835D01*
X296666Y38043D01*
X296583Y38335D01*
X296708Y38626D01*
X297000Y38835D01*
X297333Y38918D01*
X297666Y38835D01*
X297958Y38626D01*
X298083Y38335D01*
X298000Y38043D01*
X297791Y37835D01*
X297541Y37751D01*
X297125D01*
X296750Y37626D01*
X296500Y37376D01*
X296416Y37085D01*
X296500Y36793D01*
X296708Y36585D01*
X297041Y36460D01*
X297333Y36418D01*
G01X300917Y42000D02*
Y44500D01*
X301958D01*
X302292Y44375D01*
X302500Y44208D01*
X302583Y43875D01*
X302500Y43542D01*
X302250Y43333D01*
X301958Y43208D01*
X300917D01*
G01X301958D02*
X302583Y42000D01*
G01X304850D02*
Y44500D01*
X304350Y44000D01*
G01Y42000D02*
X305350D01*
G01X307158Y44083D02*
X307408Y44333D01*
X307700Y44458D01*
X308033Y44500D01*
X308450Y44417D01*
X308742Y44208D01*
X308825Y43958D01*
X308783Y43708D01*
X308617Y43500D01*
X307783Y43083D01*
X307408Y42792D01*
X307158Y42375D01*
X307075Y42000D01*
X308825D01*
G01X310967D02*
X311050Y42542D01*
X311175Y43000D01*
X311342Y43417D01*
X311550Y43875D01*
X311883Y44500D01*
X310217D01*
G01X300819Y37450D02*
Y39950D01*
X301860D01*
X302194Y39825D01*
X302402Y39658D01*
X302485Y39325D01*
X302402Y38992D01*
X302152Y38783D01*
X301860Y38658D01*
X300819D01*
G01X301860D02*
X302485Y37450D01*
G01X304752D02*
Y39950D01*
X304252Y39450D01*
G01Y37450D02*
X305252D01*
G01X307060Y39533D02*
X307310Y39783D01*
X307602Y39908D01*
X307935Y39950D01*
X308352Y39867D01*
X308644Y39658D01*
X308727Y39408D01*
X308685Y39158D01*
X308519Y38950D01*
X307685Y38533D01*
X307310Y38242D01*
X307060Y37825D01*
X306977Y37450D01*
X308727D01*
G01X310160Y38492D02*
X310452Y38783D01*
X310702Y38950D01*
X311035Y39033D01*
X311327Y38950D01*
X311535Y38783D01*
X311702Y38533D01*
X311744Y38242D01*
X311702Y37992D01*
X311535Y37742D01*
X311285Y37533D01*
X310994Y37450D01*
X310660Y37533D01*
X310369Y37783D01*
X310202Y38158D01*
X310160Y38575D01*
X310244Y39117D01*
X310369Y39408D01*
X310577Y39700D01*
X310869Y39908D01*
X311160Y39950D01*
X311452Y39867D01*
X311660Y39658D01*
G01X303819Y31720D02*
Y34220D01*
X304860D01*
X305194Y34095D01*
X305402Y33928D01*
X305485Y33595D01*
X305402Y33262D01*
X305152Y33053D01*
X304860Y32928D01*
X303819D01*
G01X304860D02*
X305485Y31720D01*
G01X307752D02*
Y34220D01*
X307252Y33720D01*
G01Y31720D02*
X308252D01*
G01X310060Y33803D02*
X310310Y34053D01*
X310602Y34178D01*
X310935Y34220D01*
X311352Y34137D01*
X311644Y33928D01*
X311727Y33678D01*
X311685Y33428D01*
X311519Y33220D01*
X310685Y32803D01*
X310310Y32512D01*
X310060Y32095D01*
X309977Y31720D01*
X311727D01*
G01X313035Y32095D02*
X313285Y31887D01*
X313577Y31762D01*
X313952Y31720D01*
X314327Y31803D01*
X314619Y31970D01*
X314827Y32262D01*
X314869Y32595D01*
X314785Y32928D01*
X314577Y33137D01*
X314285Y33303D01*
X313994Y33345D01*
X313702Y33303D01*
X313327Y33137D01*
X313452Y34220D01*
X314577D01*
G01X303815Y26310D02*
Y28810D01*
X304856D01*
X305190Y28685D01*
X305398Y28518D01*
X305481Y28185D01*
X305398Y27852D01*
X305148Y27643D01*
X304856Y27518D01*
X303815D01*
G01X304856D02*
X305481Y26310D01*
G01X307748D02*
Y28810D01*
X307248Y28310D01*
G01Y26310D02*
X308248D01*
G01X310056Y28393D02*
X310306Y28643D01*
X310598Y28768D01*
X310931Y28810D01*
X311348Y28727D01*
X311640Y28518D01*
X311723Y28268D01*
X311681Y28018D01*
X311515Y27810D01*
X310681Y27393D01*
X310306Y27102D01*
X310056Y26685D01*
X309973Y26310D01*
X311723D01*
G01X314448D02*
Y28810D01*
X312906Y27018D01*
X314990D01*
G01X290719Y32060D02*
Y34560D01*
X291760D01*
X292094Y34435D01*
X292302Y34268D01*
X292385Y33935D01*
X292302Y33602D01*
X292052Y33393D01*
X291760Y33268D01*
X290719D01*
G01X291760D02*
X292385Y32060D01*
G01X294652D02*
Y34560D01*
X294152Y34060D01*
G01Y32060D02*
X295152D01*
G01X296960Y34143D02*
X297210Y34393D01*
X297502Y34518D01*
X297835Y34560D01*
X298252Y34477D01*
X298544Y34268D01*
X298627Y34018D01*
X298585Y33768D01*
X298419Y33560D01*
X297585Y33143D01*
X297210Y32852D01*
X296960Y32435D01*
X296877Y32060D01*
X298627D01*
G01X299935Y32560D02*
X300185Y32268D01*
X300519Y32102D01*
X300894Y32060D01*
X301227Y32102D01*
X301560Y32310D01*
X301769Y32560D01*
X301810Y32810D01*
X301727Y33102D01*
X301435Y33310D01*
X301144Y33393D01*
X300769D01*
G01X301144D02*
X301394Y33518D01*
X301602Y33727D01*
X301685Y33977D01*
X301602Y34227D01*
X301394Y34435D01*
X301019Y34560D01*
X300644Y34518D01*
X300269Y34352D01*
G01X268549Y24570D02*
Y27070D01*
X269590D01*
X269924Y26945D01*
X270132Y26778D01*
X270215Y26445D01*
X270132Y26112D01*
X269882Y25903D01*
X269590Y25778D01*
X268549D01*
G01X269590D02*
X270215Y24570D01*
G01X272482D02*
Y27070D01*
X271982Y26570D01*
G01Y24570D02*
X272982D01*
G01X274790Y26653D02*
X275040Y26903D01*
X275332Y27028D01*
X275665Y27070D01*
X276082Y26987D01*
X276374Y26778D01*
X276457Y26528D01*
X276415Y26278D01*
X276249Y26070D01*
X275415Y25653D01*
X275040Y25362D01*
X274790Y24945D01*
X274707Y24570D01*
X276457D01*
G01X278682D02*
Y27070D01*
X278182Y26570D01*
G01Y24570D02*
X279182D01*
G01X268767Y80100D02*
Y82600D01*
X269808D01*
X270142Y82475D01*
X270350Y82308D01*
X270433Y81975D01*
X270350Y81642D01*
X270100Y81433D01*
X269808Y81308D01*
X268767D01*
G01X269808D02*
X270433Y80100D01*
G01X273200D02*
Y82600D01*
X271658Y80808D01*
X273742D01*
G01X275008Y81142D02*
X275300Y81433D01*
X275550Y81600D01*
X275883Y81683D01*
X276175Y81600D01*
X276383Y81433D01*
X276550Y81183D01*
X276592Y80892D01*
X276550Y80642D01*
X276383Y80392D01*
X276133Y80183D01*
X275842Y80100D01*
X275508Y80183D01*
X275217Y80433D01*
X275050Y80808D01*
X275008Y81225D01*
X275092Y81767D01*
X275217Y82058D01*
X275425Y82350D01*
X275717Y82558D01*
X276008Y82600D01*
X276300Y82517D01*
X276508Y82308D01*
G01X332400Y71600D02*
Y67600D01*
X339800D01*
G01X279200Y86917D02*
X276700D01*
Y87958D01*
X276825Y88292D01*
X276992Y88500D01*
X277325Y88583D01*
X277658Y88500D01*
X277867Y88250D01*
X277992Y87958D01*
Y86917D01*
G01Y87958D02*
X279200Y88583D01*
G01Y90850D02*
X276700D01*
X277200Y90350D01*
G01X279200D02*
Y91350D01*
G01X278158Y93158D02*
X277867Y93450D01*
X277700Y93700D01*
X277617Y94033D01*
X277700Y94325D01*
X277867Y94533D01*
X278117Y94700D01*
X278408Y94742D01*
X278658Y94700D01*
X278908Y94533D01*
X279117Y94283D01*
X279200Y93992D01*
X279117Y93658D01*
X278867Y93367D01*
X278492Y93200D01*
X278075Y93158D01*
X277533Y93242D01*
X277242Y93367D01*
X276950Y93575D01*
X276742Y93867D01*
X276700Y94158D01*
X276783Y94450D01*
X276992Y94658D01*
G01X278158Y96258D02*
X277867Y96550D01*
X277700Y96800D01*
X277617Y97133D01*
X277700Y97425D01*
X277867Y97633D01*
X278117Y97800D01*
X278408Y97842D01*
X278658Y97800D01*
X278908Y97633D01*
X279117Y97383D01*
X279200Y97092D01*
X279117Y96758D01*
X278867Y96467D01*
X278492Y96300D01*
X278075Y96258D01*
X277533Y96342D01*
X277242Y96467D01*
X276950Y96675D01*
X276742Y96967D01*
X276700Y97258D01*
X276783Y97550D01*
X276992Y97758D01*
G01X347700Y82300D02*
X343700D01*
Y74900D01*
G01X280500Y42517D02*
X278000D01*
Y43558D01*
X278125Y43892D01*
X278292Y44100D01*
X278625Y44183D01*
X278958Y44100D01*
X279167Y43850D01*
X279292Y43558D01*
Y42517D01*
G01Y43558D02*
X280500Y44183D01*
G01Y46450D02*
X278000D01*
X278500Y45950D01*
G01X280500D02*
Y46950D01*
G01X279458Y48758D02*
X279167Y49050D01*
X279000Y49300D01*
X278917Y49633D01*
X279000Y49925D01*
X279167Y50133D01*
X279417Y50300D01*
X279708Y50342D01*
X279958Y50300D01*
X280208Y50133D01*
X280417Y49883D01*
X280500Y49592D01*
X280417Y49258D01*
X280167Y48967D01*
X279792Y48800D01*
X279375Y48758D01*
X278833Y48842D01*
X278542Y48967D01*
X278250Y49175D01*
X278042Y49467D01*
X278000Y49758D01*
X278083Y50050D01*
X278292Y50258D01*
G01X280125Y51733D02*
X280333Y51983D01*
X280458Y52275D01*
X280500Y52650D01*
X280417Y53025D01*
X280250Y53317D01*
X279958Y53525D01*
X279625Y53567D01*
X279292Y53483D01*
X279083Y53275D01*
X278917Y52983D01*
X278875Y52692D01*
X278917Y52400D01*
X279083Y52025D01*
X278000Y52150D01*
Y53275D01*
G01X338300Y41300D02*
X334300D01*
Y33900D01*
G01X309048Y85275D02*
X306548D01*
Y86316D01*
X306673Y86650D01*
X306840Y86858D01*
X307173Y86941D01*
X307506Y86858D01*
X307715Y86608D01*
X307840Y86316D01*
Y85275D01*
G01Y86316D02*
X309048Y86941D01*
G01Y89208D02*
X306548D01*
X307048Y88708D01*
G01X309048D02*
Y89708D01*
G01Y92225D02*
X308506Y92308D01*
X308048Y92433D01*
X307631Y92600D01*
X307173Y92808D01*
X306548Y93141D01*
Y91475D01*
G01X308673Y94491D02*
X308881Y94741D01*
X309006Y95033D01*
X309048Y95408D01*
X308965Y95783D01*
X308798Y96075D01*
X308506Y96283D01*
X308173Y96325D01*
X307840Y96241D01*
X307631Y96033D01*
X307465Y95741D01*
X307423Y95450D01*
X307465Y95158D01*
X307631Y94783D01*
X306548Y94908D01*
Y96033D01*
G01X313218Y85275D02*
X310718D01*
Y86316D01*
X310843Y86650D01*
X311010Y86858D01*
X311343Y86941D01*
X311676Y86858D01*
X311885Y86608D01*
X312010Y86316D01*
Y85275D01*
G01Y86316D02*
X313218Y86941D01*
G01Y89208D02*
X310718D01*
X311218Y88708D01*
G01X313218D02*
Y89708D01*
G01Y92225D02*
X312676Y92308D01*
X312218Y92433D01*
X311801Y92600D01*
X311343Y92808D01*
X310718Y93141D01*
Y91475D01*
G01X313218Y95908D02*
X310718D01*
X312510Y94366D01*
Y96450D01*
G01X309030Y98419D02*
X306530D01*
Y99460D01*
X306655Y99794D01*
X306822Y100002D01*
X307155Y100085D01*
X307488Y100002D01*
X307697Y99752D01*
X307822Y99460D01*
Y98419D01*
G01Y99460D02*
X309030Y100085D01*
G01Y102352D02*
X306530D01*
X307030Y101852D01*
G01X309030D02*
Y102852D01*
G01X307988Y104660D02*
X307697Y104952D01*
X307530Y105202D01*
X307447Y105535D01*
X307530Y105827D01*
X307697Y106035D01*
X307947Y106202D01*
X308238Y106244D01*
X308488Y106202D01*
X308738Y106035D01*
X308947Y105785D01*
X309030Y105494D01*
X308947Y105160D01*
X308697Y104869D01*
X308322Y104702D01*
X307905Y104660D01*
X307363Y104744D01*
X307072Y104869D01*
X306780Y105077D01*
X306572Y105369D01*
X306530Y105660D01*
X306613Y105952D01*
X306822Y106160D01*
G01X308738Y107844D02*
X308947Y108135D01*
X309030Y108469D01*
X308947Y108802D01*
X308697Y109094D01*
X308322Y109302D01*
X307947Y109385D01*
X307488D01*
X307113Y109302D01*
X306780Y109094D01*
X306613Y108844D01*
X306530Y108552D01*
X306613Y108219D01*
X306780Y107969D01*
X307030Y107802D01*
X307363Y107719D01*
X307655Y107802D01*
X307947Y108010D01*
X308113Y108260D01*
X308155Y108552D01*
X308072Y108885D01*
X307863Y109135D01*
X307488Y109385D01*
G01X313260Y98419D02*
X310760D01*
Y99460D01*
X310885Y99794D01*
X311052Y100002D01*
X311385Y100085D01*
X311718Y100002D01*
X311927Y99752D01*
X312052Y99460D01*
Y98419D01*
G01Y99460D02*
X313260Y100085D01*
G01Y102352D02*
X310760D01*
X311260Y101852D01*
G01X313260D02*
Y102852D01*
G01X312218Y104660D02*
X311927Y104952D01*
X311760Y105202D01*
X311677Y105535D01*
X311760Y105827D01*
X311927Y106035D01*
X312177Y106202D01*
X312468Y106244D01*
X312718Y106202D01*
X312968Y106035D01*
X313177Y105785D01*
X313260Y105494D01*
X313177Y105160D01*
X312927Y104869D01*
X312552Y104702D01*
X312135Y104660D01*
X311593Y104744D01*
X311302Y104869D01*
X311010Y105077D01*
X310802Y105369D01*
X310760Y105660D01*
X310843Y105952D01*
X311052Y106160D01*
G01X313260Y108552D02*
X313218Y108844D01*
X313093Y109177D01*
X312885Y109385D01*
X312593Y109469D01*
X312302Y109385D01*
X312052Y109135D01*
X311927Y108760D01*
Y108344D01*
X311843Y108094D01*
X311635Y107885D01*
X311343Y107802D01*
X311052Y107927D01*
X310843Y108219D01*
X310760Y108552D01*
X310843Y108885D01*
X311052Y109177D01*
X311343Y109302D01*
X311635Y109219D01*
X311843Y109010D01*
X311927Y108760D01*
Y108344D01*
X312052Y107969D01*
X312302Y107719D01*
X312593Y107635D01*
X312885Y107719D01*
X313093Y107927D01*
X313218Y108260D01*
X313260Y108552D01*
G01X286385Y26311D02*
X288177D01*
X288552Y26478D01*
X288802Y26811D01*
X288885Y27228D01*
X288802Y27645D01*
X288552Y27978D01*
X288177Y28145D01*
X286385D01*
G01X286802Y29536D02*
X286552Y29786D01*
X286427Y30078D01*
X286385Y30411D01*
X286468Y30828D01*
X286677Y31120D01*
X286927Y31203D01*
X287177Y31161D01*
X287385Y30995D01*
X287802Y30161D01*
X288093Y29786D01*
X288510Y29536D01*
X288885Y29453D01*
Y31203D01*
G01X286385Y33428D02*
X286468Y33095D01*
X286677Y32845D01*
X286927Y32678D01*
X287260Y32553D01*
X287635Y32511D01*
X288010Y32553D01*
X288343Y32678D01*
X288593Y32845D01*
X288802Y33095D01*
X288885Y33428D01*
X288802Y33761D01*
X288593Y34011D01*
X288343Y34178D01*
X288010Y34303D01*
X287635Y34345D01*
X287260Y34303D01*
X286927Y34178D01*
X286677Y34011D01*
X286468Y33761D01*
X286385Y33428D01*
G01X359538Y33169D02*
X345538D01*
G01X282172Y63368D02*
X283964D01*
X284339Y63535D01*
X284589Y63868D01*
X284672Y64285D01*
X284589Y64702D01*
X284339Y65035D01*
X283964Y65202D01*
X282172D01*
G01X282589Y66593D02*
X282339Y66843D01*
X282214Y67135D01*
X282172Y67468D01*
X282255Y67885D01*
X282464Y68177D01*
X282714Y68260D01*
X282964Y68218D01*
X283172Y68052D01*
X283589Y67218D01*
X283880Y66843D01*
X284297Y66593D01*
X284672Y66510D01*
Y68260D01*
G01Y70485D02*
X282172D01*
X282672Y69985D01*
G01X284672D02*
Y70985D01*
G01X319700Y38883D02*
X321492D01*
X321867Y39050D01*
X322117Y39383D01*
X322200Y39800D01*
X322117Y40217D01*
X321867Y40550D01*
X321492Y40717D01*
X319700D01*
G01X320117Y42108D02*
X319867Y42358D01*
X319742Y42650D01*
X319700Y42983D01*
X319783Y43400D01*
X319992Y43692D01*
X320242Y43775D01*
X320492Y43733D01*
X320700Y43567D01*
X321117Y42733D01*
X321408Y42358D01*
X321825Y42108D01*
X322200Y42025D01*
Y43775D01*
G01Y46500D02*
X319700D01*
X321492Y44958D01*
Y47042D01*
G01X290746Y114526D02*
Y117026D01*
X291787D01*
X292121Y116901D01*
X292329Y116734D01*
X292412Y116401D01*
X292329Y116068D01*
X292079Y115859D01*
X291787Y115734D01*
X290746D01*
G01X291787D02*
X292412Y114526D01*
G01X294679D02*
Y117026D01*
X294179Y116526D01*
G01Y114526D02*
X295179D01*
G01X297779Y117026D02*
X297446Y116943D01*
X297196Y116734D01*
X297029Y116484D01*
X296904Y116151D01*
X296862Y115776D01*
X296904Y115401D01*
X297029Y115068D01*
X297196Y114818D01*
X297446Y114609D01*
X297779Y114526D01*
X298112Y114609D01*
X298362Y114818D01*
X298529Y115068D01*
X298654Y115401D01*
X298696Y115776D01*
X298654Y116151D01*
X298529Y116484D01*
X298362Y116734D01*
X298112Y116943D01*
X297779Y117026D01*
G01X301379Y114526D02*
Y117026D01*
X299837Y115234D01*
X301921D01*
G01X311900Y114400D02*
Y118400D01*
X304500D01*
G01X298800Y100667D02*
X296300D01*
Y101708D01*
X296425Y102042D01*
X296592Y102250D01*
X296925Y102333D01*
X297258Y102250D01*
X297467Y102000D01*
X297592Y101708D01*
Y100667D01*
G01Y101708D02*
X298800Y102333D01*
G01Y105100D02*
X296300D01*
X298092Y103558D01*
Y105642D01*
G01X296717Y106908D02*
X296467Y107158D01*
X296342Y107450D01*
X296300Y107783D01*
X296383Y108200D01*
X296592Y108492D01*
X296842Y108575D01*
X297092Y108533D01*
X297300Y108367D01*
X297717Y107533D01*
X298008Y107158D01*
X298425Y106908D01*
X298800Y106825D01*
Y108575D01*
G01X294800Y100867D02*
X292300D01*
Y101908D01*
X292425Y102242D01*
X292592Y102450D01*
X292925Y102533D01*
X293258Y102450D01*
X293467Y102200D01*
X293592Y101908D01*
Y100867D01*
G01Y101908D02*
X294800Y102533D01*
G01Y105300D02*
X292300D01*
X294092Y103758D01*
Y105842D01*
G01X294800Y107817D02*
X294258Y107900D01*
X293800Y108025D01*
X293383Y108192D01*
X292925Y108400D01*
X292300Y108733D01*
Y107067D01*
G01X327800Y172767D02*
X325300D01*
Y173808D01*
X325425Y174142D01*
X325592Y174350D01*
X325925Y174433D01*
X326258Y174350D01*
X326467Y174100D01*
X326592Y173808D01*
Y172767D01*
G01Y173808D02*
X327800Y174433D01*
G01X326758Y175908D02*
X326467Y176200D01*
X326300Y176450D01*
X326217Y176783D01*
X326300Y177075D01*
X326467Y177283D01*
X326717Y177450D01*
X327008Y177492D01*
X327258Y177450D01*
X327508Y177283D01*
X327717Y177033D01*
X327800Y176742D01*
X327717Y176408D01*
X327467Y176117D01*
X327092Y175950D01*
X326675Y175908D01*
X326133Y175992D01*
X325842Y176117D01*
X325550Y176325D01*
X325342Y176617D01*
X325300Y176908D01*
X325383Y177200D01*
X325592Y177408D01*
G01X327800Y179800D02*
X327758Y180092D01*
X327633Y180425D01*
X327425Y180633D01*
X327133Y180717D01*
X326842Y180633D01*
X326592Y180383D01*
X326467Y180008D01*
Y179592D01*
X326383Y179342D01*
X326175Y179133D01*
X325883Y179050D01*
X325592Y179175D01*
X325383Y179467D01*
X325300Y179800D01*
X325383Y180133D01*
X325592Y180425D01*
X325883Y180550D01*
X326175Y180467D01*
X326383Y180258D01*
X326467Y180008D01*
Y179592D01*
X326592Y179217D01*
X326842Y178967D01*
X327133Y178883D01*
X327425Y178967D01*
X327633Y179175D01*
X327758Y179508D01*
X327800Y179800D01*
G01X299100Y169400D02*
X303100D01*
Y176800D01*
G01X278367Y161900D02*
Y164400D01*
X279408D01*
X279742Y164275D01*
X279950Y164108D01*
X280033Y163775D01*
X279950Y163442D01*
X279700Y163233D01*
X279408Y163108D01*
X278367D01*
G01X279408D02*
X280033Y161900D01*
G01X281508Y162942D02*
X281800Y163233D01*
X282050Y163400D01*
X282383Y163483D01*
X282675Y163400D01*
X282883Y163233D01*
X283050Y162983D01*
X283092Y162692D01*
X283050Y162442D01*
X282883Y162192D01*
X282633Y161983D01*
X282342Y161900D01*
X282008Y161983D01*
X281717Y162233D01*
X281550Y162608D01*
X281508Y163025D01*
X281592Y163567D01*
X281717Y163858D01*
X281925Y164150D01*
X282217Y164358D01*
X282508Y164400D01*
X282800Y164317D01*
X283008Y164108D01*
G01X285317Y161900D02*
X285400Y162442D01*
X285525Y162900D01*
X285692Y163317D01*
X285900Y163775D01*
X286233Y164400D01*
X284567D01*
G01X281400Y170400D02*
Y166400D01*
X288800D01*
G01X331800Y175267D02*
X329300D01*
Y176308D01*
X329425Y176642D01*
X329592Y176850D01*
X329925Y176933D01*
X330258Y176850D01*
X330467Y176600D01*
X330592Y176308D01*
Y175267D01*
G01Y176308D02*
X331800Y176933D01*
G01X329717Y178408D02*
X329467Y178658D01*
X329342Y178950D01*
X329300Y179283D01*
X329383Y179700D01*
X329592Y179992D01*
X329842Y180075D01*
X330092Y180033D01*
X330300Y179867D01*
X330717Y179033D01*
X331008Y178658D01*
X331425Y178408D01*
X331800Y178325D01*
Y180075D01*
G01X331425Y181383D02*
X331633Y181633D01*
X331758Y181925D01*
X331800Y182300D01*
X331717Y182675D01*
X331550Y182967D01*
X331258Y183175D01*
X330925Y183217D01*
X330592Y183133D01*
X330383Y182925D01*
X330217Y182633D01*
X330175Y182342D01*
X330217Y182050D01*
X330383Y181675D01*
X329300Y181800D01*
Y182925D01*
G01X305000Y172700D02*
X309000D01*
Y180100D01*
G01X314367Y167900D02*
Y170400D01*
X315408D01*
X315742Y170275D01*
X315950Y170108D01*
X316033Y169775D01*
X315950Y169442D01*
X315700Y169233D01*
X315408Y169108D01*
X314367D01*
G01X315408D02*
X316033Y167900D01*
G01X317508Y169983D02*
X317758Y170233D01*
X318050Y170358D01*
X318383Y170400D01*
X318800Y170317D01*
X319092Y170108D01*
X319175Y169858D01*
X319133Y169608D01*
X318967Y169400D01*
X318133Y168983D01*
X317758Y168692D01*
X317508Y168275D01*
X317425Y167900D01*
X319175D01*
G01X321900D02*
Y170400D01*
X320358Y168608D01*
X322442D01*
G01X298800Y165600D02*
Y169600D01*
X291400D01*
G01X314367Y172100D02*
Y174600D01*
X315408D01*
X315742Y174475D01*
X315950Y174308D01*
X316033Y173975D01*
X315950Y173642D01*
X315700Y173433D01*
X315408Y173308D01*
X314367D01*
G01X315408D02*
X316033Y172100D01*
G01X317508Y174183D02*
X317758Y174433D01*
X318050Y174558D01*
X318383Y174600D01*
X318800Y174517D01*
X319092Y174308D01*
X319175Y174058D01*
X319133Y173808D01*
X318967Y173600D01*
X318133Y173183D01*
X317758Y172892D01*
X317508Y172475D01*
X317425Y172100D01*
X319175D01*
G01X320483Y172600D02*
X320733Y172308D01*
X321067Y172142D01*
X321442Y172100D01*
X321775Y172142D01*
X322108Y172350D01*
X322317Y172600D01*
X322358Y172850D01*
X322275Y173142D01*
X321983Y173350D01*
X321692Y173433D01*
X321317D01*
G01X321692D02*
X321942Y173558D01*
X322150Y173767D01*
X322233Y174017D01*
X322150Y174267D01*
X321942Y174475D01*
X321567Y174600D01*
X321192Y174558D01*
X320817Y174392D01*
G01X298800Y169800D02*
Y173800D01*
X291400D01*
G01X325225Y162133D02*
X325558Y161925D01*
X325933Y161800D01*
X326267D01*
X326600Y161925D01*
X326850Y162133D01*
X326975Y162425D01*
X326892Y162717D01*
X326683Y162967D01*
X326308Y163133D01*
X325808Y163217D01*
X325517Y163383D01*
X325392Y163675D01*
X325475Y163967D01*
X325683Y164175D01*
X325975Y164300D01*
X326267D01*
X326558Y164217D01*
X326808Y164008D01*
G01X328367Y164300D02*
Y161800D01*
X330033D01*
G01X332300D02*
X331967Y161842D01*
X331675Y162008D01*
X331425Y162258D01*
X331258Y162550D01*
X331175Y162883D01*
Y163217D01*
X331258Y163550D01*
X331425Y163842D01*
X331675Y164092D01*
X331967Y164258D01*
X332300Y164300D01*
X332633Y164258D01*
X332925Y164092D01*
X333175Y163842D01*
X333342Y163550D01*
X333425Y163217D01*
Y162883D01*
X333342Y162550D01*
X333175Y162258D01*
X332925Y162008D01*
X332633Y161842D01*
X332300Y161800D01*
G01X335400Y164300D02*
Y161800D01*
G01X334442Y164300D02*
X336358D01*
G01X337708Y163883D02*
X337958Y164133D01*
X338250Y164258D01*
X338583Y164300D01*
X339000Y164217D01*
X339292Y164008D01*
X339375Y163758D01*
X339333Y163508D01*
X339167Y163300D01*
X338333Y162883D01*
X337958Y162592D01*
X337708Y162175D01*
X337625Y161800D01*
X339375D01*
G01X268533Y169000D02*
Y167208D01*
X268700Y166833D01*
X269033Y166583D01*
X269450Y166500D01*
X269867Y166583D01*
X270200Y166833D01*
X270367Y167208D01*
Y169000D01*
G01X271758Y168583D02*
X272008Y168833D01*
X272300Y168958D01*
X272633Y169000D01*
X273050Y168917D01*
X273342Y168708D01*
X273425Y168458D01*
X273383Y168208D01*
X273217Y168000D01*
X272383Y167583D01*
X272008Y167292D01*
X271758Y166875D01*
X271675Y166500D01*
X273425D01*
G01X314017Y196392D02*
X313767Y196517D01*
X313475Y196600D01*
X313142D01*
X312767Y196475D01*
X312475Y196267D01*
X312267Y196017D01*
X312100Y195600D01*
X312058Y195225D01*
X312142Y194850D01*
X312267Y194600D01*
X312517Y194350D01*
X312808Y194183D01*
X313100Y194100D01*
X313392D01*
X313683Y194183D01*
X313933Y194308D01*
X314142Y194475D01*
G01X315283D02*
X315533Y194267D01*
X315825Y194142D01*
X316200Y194100D01*
X316575Y194183D01*
X316867Y194350D01*
X317075Y194642D01*
X317117Y194975D01*
X317033Y195308D01*
X316825Y195517D01*
X316533Y195683D01*
X316242Y195725D01*
X315950Y195683D01*
X315575Y195517D01*
X315700Y196600D01*
X316825D01*
G01X319300Y194100D02*
X319592Y194142D01*
X319925Y194267D01*
X320133Y194475D01*
X320217Y194767D01*
X320133Y195058D01*
X319883Y195308D01*
X319508Y195433D01*
X319092D01*
X318842Y195517D01*
X318633Y195725D01*
X318550Y196017D01*
X318675Y196308D01*
X318967Y196517D01*
X319300Y196600D01*
X319633Y196517D01*
X319925Y196308D01*
X320050Y196017D01*
X319967Y195725D01*
X319758Y195517D01*
X319508Y195433D01*
X319092D01*
X318717Y195308D01*
X318467Y195058D01*
X318383Y194767D01*
X318467Y194475D01*
X318675Y194267D01*
X319008Y194142D01*
X319300Y194100D01*
G01X324228Y197570D02*
Y200070D01*
X325269D01*
X325603Y199945D01*
X325811Y199778D01*
X325894Y199445D01*
X325811Y199112D01*
X325561Y198903D01*
X325269Y198778D01*
X324228D01*
G01X325269D02*
X325894Y197570D01*
G01X328161D02*
Y200070D01*
X327661Y199570D01*
G01Y197570D02*
X328661D01*
G01X331261Y200070D02*
X330928Y199987D01*
X330678Y199778D01*
X330511Y199528D01*
X330386Y199195D01*
X330344Y198820D01*
X330386Y198445D01*
X330511Y198112D01*
X330678Y197862D01*
X330928Y197653D01*
X331261Y197570D01*
X331594Y197653D01*
X331844Y197862D01*
X332011Y198112D01*
X332136Y198445D01*
X332178Y198820D01*
X332136Y199195D01*
X332011Y199528D01*
X331844Y199778D01*
X331594Y199987D01*
X331261Y200070D01*
G01X334278Y197570D02*
X334361Y198112D01*
X334486Y198570D01*
X334653Y198987D01*
X334861Y199445D01*
X335194Y200070D01*
X333528D01*
G01X300111Y200009D02*
Y196009D01*
X307511D01*
G01X324367Y193661D02*
Y196161D01*
X325408D01*
X325742Y196036D01*
X325950Y195869D01*
X326033Y195536D01*
X325950Y195203D01*
X325700Y194994D01*
X325408Y194869D01*
X324367D01*
G01X325408D02*
X326033Y193661D01*
G01X327383Y194036D02*
X327633Y193828D01*
X327925Y193703D01*
X328300Y193661D01*
X328675Y193744D01*
X328967Y193911D01*
X329175Y194203D01*
X329217Y194536D01*
X329133Y194869D01*
X328925Y195078D01*
X328633Y195244D01*
X328342Y195286D01*
X328050Y195244D01*
X327675Y195078D01*
X327800Y196161D01*
X328925D01*
G01X331400Y193661D02*
Y196161D01*
X330900Y195661D01*
G01Y193661D02*
X331900D01*
G01X300000Y195700D02*
Y191700D01*
X307400D01*
G01X324367Y189761D02*
Y192261D01*
X325408D01*
X325742Y192136D01*
X325950Y191969D01*
X326033Y191636D01*
X325950Y191303D01*
X325700Y191094D01*
X325408Y190969D01*
X324367D01*
G01X325408D02*
X326033Y189761D01*
G01X327383Y190136D02*
X327633Y189928D01*
X327925Y189803D01*
X328300Y189761D01*
X328675Y189844D01*
X328967Y190011D01*
X329175Y190303D01*
X329217Y190636D01*
X329133Y190969D01*
X328925Y191178D01*
X328633Y191344D01*
X328342Y191386D01*
X328050Y191344D01*
X327675Y191178D01*
X327800Y192261D01*
X328925D01*
G01X331400D02*
X331067Y192178D01*
X330817Y191969D01*
X330650Y191719D01*
X330525Y191386D01*
X330483Y191011D01*
X330525Y190636D01*
X330650Y190303D01*
X330817Y190053D01*
X331067Y189844D01*
X331400Y189761D01*
X331733Y189844D01*
X331983Y190053D01*
X332150Y190303D01*
X332275Y190636D01*
X332317Y191011D01*
X332275Y191386D01*
X332150Y191719D01*
X331983Y191969D01*
X331733Y192178D01*
X331400Y192261D01*
G01X300000Y191700D02*
Y187700D01*
X307400D01*
G01X313267Y184100D02*
Y186600D01*
X314308D01*
X314642Y186475D01*
X314850Y186308D01*
X314933Y185975D01*
X314850Y185642D01*
X314600Y185433D01*
X314308Y185308D01*
X313267D01*
G01X314308D02*
X314933Y184100D01*
G01X317200D02*
Y186600D01*
X316700Y186100D01*
G01Y184100D02*
X317700D01*
G01X320300D02*
X320592Y184142D01*
X320925Y184267D01*
X321133Y184475D01*
X321217Y184767D01*
X321133Y185058D01*
X320883Y185308D01*
X320508Y185433D01*
X320092D01*
X319842Y185517D01*
X319633Y185725D01*
X319550Y186017D01*
X319675Y186308D01*
X319967Y186517D01*
X320300Y186600D01*
X320633Y186517D01*
X320925Y186308D01*
X321050Y186017D01*
X320967Y185725D01*
X320758Y185517D01*
X320508Y185433D01*
X320092D01*
X319717Y185308D01*
X319467Y185058D01*
X319383Y184767D01*
X319467Y184475D01*
X319675Y184267D01*
X320008Y184142D01*
X320300Y184100D01*
G01X291400Y189800D02*
Y185800D01*
X298800D01*
G01X336200Y181367D02*
X333700D01*
Y182408D01*
X333825Y182742D01*
X333992Y182950D01*
X334325Y183033D01*
X334658Y182950D01*
X334867Y182700D01*
X334992Y182408D01*
Y181367D01*
G01Y182408D02*
X336200Y183033D01*
G01X334117Y184508D02*
X333867Y184758D01*
X333742Y185050D01*
X333700Y185383D01*
X333783Y185800D01*
X333992Y186092D01*
X334242Y186175D01*
X334492Y186133D01*
X334700Y185967D01*
X335117Y185133D01*
X335408Y184758D01*
X335825Y184508D01*
X336200Y184425D01*
Y186175D01*
G01X335158Y187608D02*
X334867Y187900D01*
X334700Y188150D01*
X334617Y188483D01*
X334700Y188775D01*
X334867Y188983D01*
X335117Y189150D01*
X335408Y189192D01*
X335658Y189150D01*
X335908Y188983D01*
X336117Y188733D01*
X336200Y188442D01*
X336117Y188108D01*
X335867Y187817D01*
X335492Y187650D01*
X335075Y187608D01*
X334533Y187692D01*
X334242Y187817D01*
X333950Y188025D01*
X333742Y188317D01*
X333700Y188608D01*
X333783Y188900D01*
X333992Y189108D01*
G01X309000Y187600D02*
X305000D01*
Y180200D01*
G01X415217Y-2200D02*
Y300D01*
X416258D01*
X416592Y175D01*
X416800Y8D01*
X416883Y-325D01*
X416800Y-658D01*
X416550Y-867D01*
X416258Y-992D01*
X415217D01*
G01X416258D02*
X416883Y-2200D01*
G01X419150D02*
Y300D01*
X418650Y-200D01*
G01Y-2200D02*
X419650D01*
G01X422250D02*
Y300D01*
X421750Y-200D01*
G01Y-2200D02*
X422750D01*
G01X424642Y-1908D02*
X424933Y-2117D01*
X425267Y-2200D01*
X425600Y-2117D01*
X425892Y-1867D01*
X426100Y-1492D01*
X426183Y-1117D01*
Y-658D01*
X426100Y-283D01*
X425892Y50D01*
X425642Y217D01*
X425350Y300D01*
X425017Y217D01*
X424767Y50D01*
X424600Y-200D01*
X424517Y-533D01*
X424600Y-825D01*
X424808Y-1117D01*
X425058Y-1283D01*
X425350Y-1325D01*
X425683Y-1242D01*
X425933Y-1033D01*
X426183Y-658D01*
G01X409450Y-2998D02*
X413450D01*
Y4402D01*
G01X418167Y13992D02*
X417917Y14117D01*
X417625Y14200D01*
X417292D01*
X416917Y14075D01*
X416625Y13867D01*
X416417Y13617D01*
X416250Y13200D01*
X416208Y12825D01*
X416292Y12450D01*
X416417Y12200D01*
X416667Y11950D01*
X416958Y11783D01*
X417250Y11700D01*
X417542D01*
X417833Y11783D01*
X418083Y11908D01*
X418292Y12075D01*
G01X419433Y14200D02*
Y12408D01*
X419600Y12033D01*
X419933Y11783D01*
X420350Y11700D01*
X420767Y11783D01*
X421100Y12033D01*
X421267Y12408D01*
Y14200D01*
G01X422658Y12742D02*
X422950Y13033D01*
X423200Y13200D01*
X423533Y13283D01*
X423825Y13200D01*
X424033Y13033D01*
X424200Y12783D01*
X424242Y12492D01*
X424200Y12242D01*
X424033Y11992D01*
X423783Y11783D01*
X423492Y11700D01*
X423158Y11783D01*
X422867Y12033D01*
X422700Y12408D01*
X422658Y12825D01*
X422742Y13367D01*
X422867Y13658D01*
X423075Y13950D01*
X423367Y14158D01*
X423658Y14200D01*
X423950Y14117D01*
X424158Y13908D01*
G01X426550Y14200D02*
X426217Y14117D01*
X425967Y13908D01*
X425800Y13658D01*
X425675Y13325D01*
X425633Y12950D01*
X425675Y12575D01*
X425800Y12242D01*
X425967Y11992D01*
X426217Y11783D01*
X426550Y11700D01*
X426883Y11783D01*
X427133Y11992D01*
X427300Y12242D01*
X427425Y12575D01*
X427467Y12950D01*
X427425Y13325D01*
X427300Y13658D01*
X427133Y13908D01*
X426883Y14117D01*
X426550Y14200D01*
G01X371700Y23500D02*
Y19500D01*
X379100D01*
G01X378700Y-3200D02*
Y800D01*
X371300D01*
G01X398200Y-900D02*
X402200D01*
Y6500D01*
G01X378900Y1300D02*
Y5300D01*
X371500D01*
G01X389100Y19700D02*
Y23700D01*
X381700D01*
G01X371687Y19368D02*
Y15368D01*
X379087D01*
G01X379083Y11318D02*
Y15318D01*
X371683D01*
G01X389100Y15300D02*
Y19300D01*
X381700D01*
G01Y15200D02*
Y11200D01*
X389100D01*
G01X389200Y5400D02*
Y9400D01*
X381800D01*
G01Y5300D02*
Y1300D01*
X389200D01*
G01X371500Y9400D02*
Y5400D01*
X378900D01*
G01X416367Y7561D02*
Y10061D01*
X417408D01*
X417742Y9936D01*
X417950Y9769D01*
X418033Y9436D01*
X417950Y9103D01*
X417700Y8894D01*
X417408Y8769D01*
X416367D01*
G01X417408D02*
X418033Y7561D01*
G01X419383Y10061D02*
Y8269D01*
X419550Y7894D01*
X419883Y7644D01*
X420300Y7561D01*
X420717Y7644D01*
X421050Y7894D01*
X421217Y8269D01*
Y10061D01*
G01X423400Y7561D02*
Y10061D01*
X422900Y9561D01*
G01Y7561D02*
X423900D01*
G01X425583Y7936D02*
X425833Y7728D01*
X426125Y7603D01*
X426500Y7561D01*
X426875Y7644D01*
X427167Y7811D01*
X427375Y8103D01*
X427417Y8436D01*
X427333Y8769D01*
X427125Y8978D01*
X426833Y9144D01*
X426542Y9186D01*
X426250Y9144D01*
X425875Y8978D01*
X426000Y10061D01*
X427125D01*
G01X428683Y8061D02*
X428933Y7769D01*
X429267Y7603D01*
X429642Y7561D01*
X429975Y7603D01*
X430308Y7811D01*
X430517Y8061D01*
X430558Y8311D01*
X430475Y8603D01*
X430183Y8811D01*
X429892Y8894D01*
X429517D01*
G01X429892D02*
X430142Y9019D01*
X430350Y9228D01*
X430433Y9478D01*
X430350Y9728D01*
X430142Y9936D01*
X429767Y10061D01*
X429392Y10019D01*
X429017Y9853D01*
G01X411800Y17300D02*
X415800D01*
Y24700D01*
G01X365600Y-3800D02*
Y200D01*
X358200D01*
G01X415067Y2300D02*
Y4800D01*
X416108D01*
X416442Y4675D01*
X416650Y4508D01*
X416733Y4175D01*
X416650Y3842D01*
X416400Y3633D01*
X416108Y3508D01*
X415067D01*
G01X416108D02*
X416733Y2300D01*
G01X418083Y4800D02*
Y3008D01*
X418250Y2633D01*
X418583Y2383D01*
X419000Y2300D01*
X419417Y2383D01*
X419750Y2633D01*
X419917Y3008D01*
Y4800D01*
G01X422100Y2300D02*
Y4800D01*
X421600Y4300D01*
G01Y2300D02*
X422600D01*
G01X424283Y2675D02*
X424533Y2467D01*
X424825Y2342D01*
X425200Y2300D01*
X425575Y2383D01*
X425867Y2550D01*
X426075Y2842D01*
X426117Y3175D01*
X426033Y3508D01*
X425825Y3717D01*
X425533Y3883D01*
X425242Y3925D01*
X424950Y3883D01*
X424575Y3717D01*
X424700Y4800D01*
X425825D01*
G01X427508Y4383D02*
X427758Y4633D01*
X428050Y4758D01*
X428383Y4800D01*
X428800Y4717D01*
X429092Y4508D01*
X429175Y4258D01*
X429133Y4008D01*
X428967Y3800D01*
X428133Y3383D01*
X427758Y3092D01*
X427508Y2675D01*
X427425Y2300D01*
X429175D01*
G01X415800Y17200D02*
X411800D01*
Y9800D01*
G01X359538Y33169D02*
Y2469D01*
G01X394240Y24502D02*
Y16502D01*
X406190D01*
Y24502D01*
X394240D01*
G01X406190Y18352D02*
X404190Y20352D01*
X406190Y22352D01*
G01X408319Y63960D02*
X411319D01*
G01X420319Y41160D02*
Y38160D01*
G01X409319Y54060D02*
X411319D01*
G01X426219Y72960D02*
Y70960D01*
G01X410419Y45260D02*
Y40260D01*
X415419D01*
G01Y71860D02*
X410419D01*
Y66860D01*
G01X418117Y36992D02*
X417867Y37117D01*
X417575Y37200D01*
X417242D01*
X416867Y37075D01*
X416575Y36867D01*
X416367Y36617D01*
X416200Y36200D01*
X416158Y35825D01*
X416242Y35450D01*
X416367Y35200D01*
X416617Y34950D01*
X416908Y34783D01*
X417200Y34700D01*
X417492D01*
X417783Y34783D01*
X418033Y34908D01*
X418242Y35075D01*
G01X419383Y37200D02*
Y35408D01*
X419550Y35033D01*
X419883Y34783D01*
X420300Y34700D01*
X420717Y34783D01*
X421050Y35033D01*
X421217Y35408D01*
Y37200D01*
G01X422608Y35742D02*
X422900Y36033D01*
X423150Y36200D01*
X423483Y36283D01*
X423775Y36200D01*
X423983Y36033D01*
X424150Y35783D01*
X424192Y35492D01*
X424150Y35242D01*
X423983Y34992D01*
X423733Y34783D01*
X423442Y34700D01*
X423108Y34783D01*
X422817Y35033D01*
X422650Y35408D01*
X422608Y35825D01*
X422692Y36367D01*
X422817Y36658D01*
X423025Y36950D01*
X423317Y37158D01*
X423608Y37200D01*
X423900Y37117D01*
X424108Y36908D01*
G01X379100Y23600D02*
Y27600D01*
X371700D01*
G01X382000Y67500D02*
Y71500D01*
X374600D01*
G01X377600Y83700D02*
X373600D01*
Y76300D01*
G01X415477Y90493D02*
X412977D01*
Y91534D01*
X413102Y91868D01*
X413269Y92076D01*
X413602Y92159D01*
X413935Y92076D01*
X414144Y91826D01*
X414269Y91534D01*
Y90493D01*
G01Y91534D02*
X415477Y92159D01*
G01X412977Y93509D02*
X414769D01*
X415144Y93676D01*
X415394Y94009D01*
X415477Y94426D01*
X415394Y94843D01*
X415144Y95176D01*
X414769Y95343D01*
X412977D01*
G01X413394Y96734D02*
X413144Y96984D01*
X413019Y97276D01*
X412977Y97609D01*
X413060Y98026D01*
X413269Y98318D01*
X413519Y98401D01*
X413769Y98359D01*
X413977Y98193D01*
X414394Y97359D01*
X414685Y96984D01*
X415102Y96734D01*
X415477Y96651D01*
Y98401D01*
G01X415185Y99918D02*
X415394Y100209D01*
X415477Y100543D01*
X415394Y100876D01*
X415144Y101168D01*
X414769Y101376D01*
X414394Y101459D01*
X413935D01*
X413560Y101376D01*
X413227Y101168D01*
X413060Y100918D01*
X412977Y100626D01*
X413060Y100293D01*
X413227Y100043D01*
X413477Y99876D01*
X413810Y99793D01*
X414102Y99876D01*
X414394Y100084D01*
X414560Y100334D01*
X414602Y100626D01*
X414519Y100959D01*
X414310Y101209D01*
X413935Y101459D01*
G01X424638Y86076D02*
X420638D01*
Y78676D01*
G01X410783Y90164D02*
X408283D01*
Y91205D01*
X408408Y91539D01*
X408575Y91747D01*
X408908Y91830D01*
X409241Y91747D01*
X409450Y91497D01*
X409575Y91205D01*
Y90164D01*
G01Y91205D02*
X410783Y91830D01*
G01X408283Y93180D02*
X410075D01*
X410450Y93347D01*
X410700Y93680D01*
X410783Y94097D01*
X410700Y94514D01*
X410450Y94847D01*
X410075Y95014D01*
X408283D01*
G01X408700Y96405D02*
X408450Y96655D01*
X408325Y96947D01*
X408283Y97280D01*
X408366Y97697D01*
X408575Y97989D01*
X408825Y98072D01*
X409075Y98030D01*
X409283Y97864D01*
X409700Y97030D01*
X409991Y96655D01*
X410408Y96405D01*
X410783Y96322D01*
Y98072D01*
G01Y100214D02*
X410241Y100297D01*
X409783Y100422D01*
X409366Y100589D01*
X408908Y100797D01*
X408283Y101130D01*
Y99464D01*
G01X420444Y86047D02*
X416444D01*
Y78647D01*
G01X419535Y90521D02*
X417035D01*
Y91562D01*
X417160Y91896D01*
X417327Y92104D01*
X417660Y92187D01*
X417993Y92104D01*
X418202Y91854D01*
X418327Y91562D01*
Y90521D01*
G01Y91562D02*
X419535Y92187D01*
G01X417035Y93537D02*
X418827D01*
X419202Y93704D01*
X419452Y94037D01*
X419535Y94454D01*
X419452Y94871D01*
X419202Y95204D01*
X418827Y95371D01*
X417035D01*
G01X417452Y96762D02*
X417202Y97012D01*
X417077Y97304D01*
X417035Y97637D01*
X417118Y98054D01*
X417327Y98346D01*
X417577Y98429D01*
X417827Y98387D01*
X418035Y98221D01*
X418452Y97387D01*
X418743Y97012D01*
X419160Y96762D01*
X419535Y96679D01*
Y98429D01*
G01X418493Y99862D02*
X418202Y100154D01*
X418035Y100404D01*
X417952Y100737D01*
X418035Y101029D01*
X418202Y101237D01*
X418452Y101404D01*
X418743Y101446D01*
X418993Y101404D01*
X419243Y101237D01*
X419452Y100987D01*
X419535Y100696D01*
X419452Y100362D01*
X419202Y100071D01*
X418827Y99904D01*
X418410Y99862D01*
X417868Y99946D01*
X417577Y100071D01*
X417285Y100279D01*
X417077Y100571D01*
X417035Y100862D01*
X417118Y101154D01*
X417327Y101362D01*
G01X428696Y86104D02*
X424696D01*
Y78704D01*
G01X406622Y90193D02*
X404122D01*
Y91234D01*
X404247Y91568D01*
X404414Y91776D01*
X404747Y91859D01*
X405080Y91776D01*
X405289Y91526D01*
X405414Y91234D01*
Y90193D01*
G01Y91234D02*
X406622Y91859D01*
G01X404122Y93209D02*
X405914D01*
X406289Y93376D01*
X406539Y93709D01*
X406622Y94126D01*
X406539Y94543D01*
X406289Y94876D01*
X405914Y95043D01*
X404122D01*
G01X404539Y96434D02*
X404289Y96684D01*
X404164Y96976D01*
X404122Y97309D01*
X404205Y97726D01*
X404414Y98018D01*
X404664Y98101D01*
X404914Y98059D01*
X405122Y97893D01*
X405539Y97059D01*
X405830Y96684D01*
X406247Y96434D01*
X406622Y96351D01*
Y98101D01*
G01X406122Y99409D02*
X406414Y99659D01*
X406580Y99993D01*
X406622Y100368D01*
X406580Y100701D01*
X406372Y101034D01*
X406122Y101243D01*
X405872Y101284D01*
X405580Y101201D01*
X405372Y100909D01*
X405289Y100618D01*
Y100243D01*
G01Y100618D02*
X405164Y100868D01*
X404955Y101076D01*
X404705Y101159D01*
X404455Y101076D01*
X404247Y100868D01*
X404122Y100493D01*
X404164Y100118D01*
X404330Y99743D01*
G01X416283Y86076D02*
X412283D01*
Y78676D01*
G01X424465Y32637D02*
Y28637D01*
X431865D01*
G01X424200Y28700D02*
Y32700D01*
X416800D01*
G01X392200Y53500D02*
Y57500D01*
X384800D01*
G01X424100Y24400D02*
Y28400D01*
X416700D01*
G01X424400Y28500D02*
Y24500D01*
X431800D01*
G01X373500Y83700D02*
X369500D01*
Y76300D01*
G01X383800Y32200D02*
Y36200D01*
X376400D01*
G01X383800Y28100D02*
Y32100D01*
X376400D01*
G01X392300Y63400D02*
Y67400D01*
X384900D01*
G01Y71500D02*
Y67500D01*
X392300D01*
G01X384800Y61600D02*
Y57600D01*
X392200D01*
G01X374600Y67400D02*
Y63400D01*
X382000D01*
G01X374813Y57568D02*
Y53568D01*
X382213D01*
G01X382217Y57618D02*
Y61618D01*
X374817D01*
G01X392200Y48700D02*
Y52700D01*
X384800D01*
G01Y48600D02*
Y44600D01*
X392200D01*
G01X374800Y52700D02*
Y48700D01*
X382200D01*
G01Y44600D02*
Y48600D01*
X374800D01*
G01X374700Y40400D02*
Y36400D01*
X382100D01*
G01X382200Y40500D02*
Y44500D01*
X374800D01*
G01X381700Y27800D02*
Y23800D01*
X389100D01*
G01X397148Y74958D02*
X393148D01*
Y67558D01*
G01X401318Y74958D02*
X397318D01*
Y67558D01*
G01X393130Y76202D02*
X397130D01*
Y83602D01*
G01X397360Y76202D02*
X401360D01*
Y83602D01*
G01X352538Y32069D02*
X353638Y33169D01*
G01X352538Y32069D02*
X351438Y33169D01*
G01X348738Y39469D02*
Y70169D01*
G01X362738Y39469D02*
X348738D01*
G01X362738Y70169D02*
Y39469D01*
G01Y70169D02*
X348738D01*
G01X355738Y69069D02*
X356838Y70169D01*
G01X355738Y69069D02*
X354638Y70169D01*
G01X421325Y194633D02*
X421658Y194425D01*
X422033Y194300D01*
X422367D01*
X422700Y194425D01*
X422950Y194633D01*
X423075Y194925D01*
X422992Y195217D01*
X422783Y195467D01*
X422408Y195633D01*
X421908Y195717D01*
X421617Y195883D01*
X421492Y196175D01*
X421575Y196467D01*
X421783Y196675D01*
X422075Y196800D01*
X422367D01*
X422658Y196717D01*
X422908Y196508D01*
G01X424467Y196800D02*
Y194300D01*
X426133D01*
G01X428400D02*
X428067Y194342D01*
X427775Y194508D01*
X427525Y194758D01*
X427358Y195050D01*
X427275Y195383D01*
Y195717D01*
X427358Y196050D01*
X427525Y196342D01*
X427775Y196592D01*
X428067Y196758D01*
X428400Y196800D01*
X428733Y196758D01*
X429025Y196592D01*
X429275Y196342D01*
X429442Y196050D01*
X429525Y195717D01*
Y195383D01*
X429442Y195050D01*
X429275Y194758D01*
X429025Y194508D01*
X428733Y194342D01*
X428400Y194300D01*
G01X431500Y196800D02*
Y194300D01*
G01X430542Y196800D02*
X432458D01*
G01X433683Y194800D02*
X433933Y194508D01*
X434267Y194342D01*
X434642Y194300D01*
X434975Y194342D01*
X435308Y194550D01*
X435517Y194800D01*
X435558Y195050D01*
X435475Y195342D01*
X435183Y195550D01*
X434892Y195633D01*
X434517D01*
G01X434892D02*
X435142Y195758D01*
X435350Y195967D01*
X435433Y196217D01*
X435350Y196467D01*
X435142Y196675D01*
X434767Y196800D01*
X434392Y196758D01*
X434017Y196592D01*
G01X442300Y11967D02*
X444800D01*
Y13633D01*
G01X442300Y14983D02*
X444092D01*
X444467Y15150D01*
X444717Y15483D01*
X444800Y15900D01*
X444717Y16317D01*
X444467Y16650D01*
X444092Y16817D01*
X442300D01*
G01X442717Y18208D02*
X442467Y18458D01*
X442342Y18750D01*
X442300Y19083D01*
X442383Y19500D01*
X442592Y19792D01*
X442842Y19875D01*
X443092Y19833D01*
X443300Y19667D01*
X443717Y18833D01*
X444008Y18458D01*
X444425Y18208D01*
X444800Y18125D01*
Y19875D01*
G01X457184Y13674D02*
X454684D01*
Y14715D01*
X454809Y15049D01*
X454976Y15257D01*
X455309Y15340D01*
X455642Y15257D01*
X455851Y15007D01*
X455976Y14715D01*
Y13674D01*
G01Y14715D02*
X457184Y15340D01*
G01X454684Y16690D02*
X456476D01*
X456851Y16857D01*
X457101Y17190D01*
X457184Y17607D01*
X457101Y18024D01*
X456851Y18357D01*
X456476Y18524D01*
X454684D01*
G01X456892Y19999D02*
X457101Y20290D01*
X457184Y20624D01*
X457101Y20957D01*
X456851Y21249D01*
X456476Y21457D01*
X456101Y21540D01*
X455642D01*
X455267Y21457D01*
X454934Y21249D01*
X454767Y20999D01*
X454684Y20707D01*
X454767Y20374D01*
X454934Y20124D01*
X455184Y19957D01*
X455517Y19874D01*
X455809Y19957D01*
X456101Y20165D01*
X456267Y20415D01*
X456309Y20707D01*
X456226Y21040D01*
X456017Y21290D01*
X455642Y21540D01*
G01X443182Y3498D02*
Y5998D01*
X444223D01*
X444557Y5873D01*
X444765Y5706D01*
X444848Y5373D01*
X444765Y5040D01*
X444515Y4831D01*
X444223Y4706D01*
X443182D01*
G01X444223D02*
X444848Y3498D01*
G01X446198Y5998D02*
Y4206D01*
X446365Y3831D01*
X446698Y3581D01*
X447115Y3498D01*
X447532Y3581D01*
X447865Y3831D01*
X448032Y4206D01*
Y5998D01*
G01X449423Y5581D02*
X449673Y5831D01*
X449965Y5956D01*
X450298Y5998D01*
X450715Y5915D01*
X451007Y5706D01*
X451090Y5456D01*
X451048Y5206D01*
X450882Y4998D01*
X450048Y4581D01*
X449673Y4290D01*
X449423Y3873D01*
X449340Y3498D01*
X451090D01*
G01X453315D02*
X453607Y3540D01*
X453940Y3665D01*
X454148Y3873D01*
X454232Y4165D01*
X454148Y4456D01*
X453898Y4706D01*
X453523Y4831D01*
X453107D01*
X452857Y4915D01*
X452648Y5123D01*
X452565Y5415D01*
X452690Y5706D01*
X452982Y5915D01*
X453315Y5998D01*
X453648Y5915D01*
X453940Y5706D01*
X454065Y5415D01*
X453982Y5123D01*
X453773Y4915D01*
X453523Y4831D01*
X453107D01*
X452732Y4706D01*
X452482Y4456D01*
X452398Y4165D01*
X452482Y3873D01*
X452690Y3665D01*
X453023Y3540D01*
X453315Y3498D01*
G01X453157Y12152D02*
X450657D01*
Y13193D01*
X450782Y13527D01*
X450949Y13735D01*
X451282Y13818D01*
X451615Y13735D01*
X451824Y13485D01*
X451949Y13193D01*
Y12152D01*
G01Y13193D02*
X453157Y13818D01*
G01X450657Y15168D02*
X452449D01*
X452824Y15335D01*
X453074Y15668D01*
X453157Y16085D01*
X453074Y16502D01*
X452824Y16835D01*
X452449Y17002D01*
X450657D01*
G01X451074Y18393D02*
X450824Y18643D01*
X450699Y18935D01*
X450657Y19268D01*
X450740Y19685D01*
X450949Y19977D01*
X451199Y20060D01*
X451449Y20018D01*
X451657Y19852D01*
X452074Y19018D01*
X452365Y18643D01*
X452782Y18393D01*
X453157Y18310D01*
Y20060D01*
G01X452782Y21368D02*
X452990Y21618D01*
X453115Y21910D01*
X453157Y22285D01*
X453074Y22660D01*
X452907Y22952D01*
X452615Y23160D01*
X452282Y23202D01*
X451949Y23118D01*
X451740Y22910D01*
X451574Y22618D01*
X451532Y22327D01*
X451574Y22035D01*
X451740Y21660D01*
X450657Y21785D01*
Y22910D01*
G01X460745Y15248D02*
Y17748D01*
X461786D01*
X462120Y17623D01*
X462328Y17456D01*
X462411Y17123D01*
X462328Y16790D01*
X462078Y16581D01*
X461786Y16456D01*
X460745D01*
G01X461786D02*
X462411Y15248D01*
G01X463761Y17748D02*
Y15956D01*
X463928Y15581D01*
X464261Y15331D01*
X464678Y15248D01*
X465095Y15331D01*
X465428Y15581D01*
X465595Y15956D01*
Y17748D01*
G01X466986Y17331D02*
X467236Y17581D01*
X467528Y17706D01*
X467861Y17748D01*
X468278Y17665D01*
X468570Y17456D01*
X468653Y17206D01*
X468611Y16956D01*
X468445Y16748D01*
X467611Y16331D01*
X467236Y16040D01*
X466986Y15623D01*
X466903Y15248D01*
X468653D01*
G01X470086Y17331D02*
X470336Y17581D01*
X470628Y17706D01*
X470961Y17748D01*
X471378Y17665D01*
X471670Y17456D01*
X471753Y17206D01*
X471711Y16956D01*
X471545Y16748D01*
X470711Y16331D01*
X470336Y16040D01*
X470086Y15623D01*
X470003Y15248D01*
X471753D01*
G01X449026Y12125D02*
X446526D01*
Y13166D01*
X446651Y13500D01*
X446818Y13708D01*
X447151Y13791D01*
X447484Y13708D01*
X447693Y13458D01*
X447818Y13166D01*
Y12125D01*
G01Y13166D02*
X449026Y13791D01*
G01X446526Y15141D02*
X448318D01*
X448693Y15308D01*
X448943Y15641D01*
X449026Y16058D01*
X448943Y16475D01*
X448693Y16808D01*
X448318Y16975D01*
X446526D01*
G01X446943Y18366D02*
X446693Y18616D01*
X446568Y18908D01*
X446526Y19241D01*
X446609Y19658D01*
X446818Y19950D01*
X447068Y20033D01*
X447318Y19991D01*
X447526Y19825D01*
X447943Y18991D01*
X448234Y18616D01*
X448651Y18366D01*
X449026Y18283D01*
Y20033D01*
G01X446526Y22258D02*
X446609Y21925D01*
X446818Y21675D01*
X447068Y21508D01*
X447401Y21383D01*
X447776Y21341D01*
X448151Y21383D01*
X448484Y21508D01*
X448734Y21675D01*
X448943Y21925D01*
X449026Y22258D01*
X448943Y22591D01*
X448734Y22841D01*
X448484Y23008D01*
X448151Y23133D01*
X447776Y23175D01*
X447401Y23133D01*
X447068Y23008D01*
X446818Y22841D01*
X446609Y22591D01*
X446526Y22258D01*
G01X430817Y3761D02*
Y6261D01*
X431858D01*
X432192Y6136D01*
X432400Y5969D01*
X432483Y5636D01*
X432400Y5303D01*
X432150Y5094D01*
X431858Y4969D01*
X430817D01*
G01X431858D02*
X432483Y3761D01*
G01X433833Y6261D02*
Y4469D01*
X434000Y4094D01*
X434333Y3844D01*
X434750Y3761D01*
X435167Y3844D01*
X435500Y4094D01*
X435667Y4469D01*
Y6261D01*
G01X436933Y4261D02*
X437183Y3969D01*
X437517Y3803D01*
X437892Y3761D01*
X438225Y3803D01*
X438558Y4011D01*
X438767Y4261D01*
X438808Y4511D01*
X438725Y4803D01*
X438433Y5011D01*
X438142Y5094D01*
X437767D01*
G01X438142D02*
X438392Y5219D01*
X438600Y5428D01*
X438683Y5678D01*
X438600Y5928D01*
X438392Y6136D01*
X438017Y6261D01*
X437642Y6219D01*
X437267Y6053D01*
G01X441450Y3761D02*
Y6261D01*
X439908Y4469D01*
X441992D01*
G01X431067Y-339D02*
Y2161D01*
X432108D01*
X432442Y2036D01*
X432650Y1869D01*
X432733Y1536D01*
X432650Y1203D01*
X432400Y994D01*
X432108Y869D01*
X431067D01*
G01X432108D02*
X432733Y-339D01*
G01X434292Y-47D02*
X434583Y-256D01*
X434917Y-339D01*
X435250Y-256D01*
X435542Y-6D01*
X435750Y369D01*
X435833Y744D01*
Y1203D01*
X435750Y1578D01*
X435542Y1911D01*
X435292Y2078D01*
X435000Y2161D01*
X434667Y2078D01*
X434417Y1911D01*
X434250Y1661D01*
X434167Y1328D01*
X434250Y1036D01*
X434458Y744D01*
X434708Y578D01*
X435000Y536D01*
X435333Y619D01*
X435583Y828D01*
X435833Y1203D01*
G01X437392Y-47D02*
X437683Y-256D01*
X438017Y-339D01*
X438350Y-256D01*
X438642Y-6D01*
X438850Y369D01*
X438933Y744D01*
Y1203D01*
X438850Y1578D01*
X438642Y1911D01*
X438392Y2078D01*
X438100Y2161D01*
X437767Y2078D01*
X437517Y1911D01*
X437350Y1661D01*
X437267Y1328D01*
X437350Y1036D01*
X437558Y744D01*
X437808Y578D01*
X438100Y536D01*
X438433Y619D01*
X438683Y828D01*
X438933Y1203D01*
G01X443167Y-639D02*
Y1861D01*
X444208D01*
X444542Y1736D01*
X444750Y1569D01*
X444833Y1236D01*
X444750Y903D01*
X444500Y694D01*
X444208Y569D01*
X443167D01*
G01X444208D02*
X444833Y-639D01*
G01X446392Y-347D02*
X446683Y-556D01*
X447017Y-639D01*
X447350Y-556D01*
X447642Y-306D01*
X447850Y69D01*
X447933Y444D01*
Y903D01*
X447850Y1278D01*
X447642Y1611D01*
X447392Y1778D01*
X447100Y1861D01*
X446767Y1778D01*
X446517Y1611D01*
X446350Y1361D01*
X446267Y1028D01*
X446350Y736D01*
X446558Y444D01*
X446808Y278D01*
X447100Y236D01*
X447433Y319D01*
X447683Y528D01*
X447933Y903D01*
G01X450117Y-639D02*
X450200Y-97D01*
X450325Y361D01*
X450492Y778D01*
X450700Y1236D01*
X451033Y1861D01*
X449367D01*
G01X478555Y-48956D02*
X479388D01*
Y-49706D01*
X479138Y-49956D01*
X478847Y-50123D01*
X478430Y-50206D01*
X478013Y-50123D01*
X477722Y-49956D01*
X477472Y-49706D01*
X477305Y-49414D01*
X477222Y-49081D01*
Y-48789D01*
X477305Y-48539D01*
X477472Y-48248D01*
X477722Y-47998D01*
X477972Y-47831D01*
X478305Y-47706D01*
X478597D01*
X478930Y-47789D01*
X479180Y-47956D01*
G01X480613Y-50206D02*
Y-47706D01*
X482197D01*
G01X481613Y-48914D02*
X480613D01*
G01X484505Y-50206D02*
Y-47706D01*
X484005Y-48206D01*
G01Y-50206D02*
X485005D01*
G01X444450Y96700D02*
X447950Y101700D01*
G01X444450D02*
X447950Y96700D01*
G01X449967Y101700D02*
Y98117D01*
X450300Y97367D01*
X450967Y96867D01*
X451800Y96700D01*
X452633Y96867D01*
X453300Y97367D01*
X453633Y98117D01*
Y101700D01*
G01X457400Y96700D02*
Y101700D01*
X456400Y100700D01*
G01Y96700D02*
X458400D01*
G01X463000Y96533D02*
X462833Y96617D01*
Y96783D01*
X463000Y96867D01*
X463167Y96783D01*
Y96617D01*
X463000Y96533D01*
G01Y98783D02*
X462833Y98867D01*
Y99033D01*
X463000Y99117D01*
X463167Y99033D01*
Y98867D01*
X463000Y98783D01*
G01X467017Y100867D02*
X467517Y101367D01*
X468100Y101617D01*
X468767Y101700D01*
X469600Y101533D01*
X470183Y101117D01*
X470350Y100617D01*
X470267Y100117D01*
X469933Y99700D01*
X468267Y98867D01*
X467517Y98283D01*
X467017Y97450D01*
X466850Y96700D01*
X470350D01*
G01X475200D02*
Y101700D01*
X472117Y98117D01*
X476283D01*
G01X477633Y96700D02*
Y101700D01*
X479800Y97533D01*
X481967Y101700D01*
Y96700D01*
G01X483650D02*
Y101700D01*
G01X487150D02*
Y96700D01*
G01Y99200D02*
X483650D01*
G01X489417Y101700D02*
X492583D01*
X489417Y96700D01*
X492583D01*
G01X474000Y61283D02*
X475792D01*
X476167Y61450D01*
X476417Y61783D01*
X476500Y62200D01*
X476417Y62617D01*
X476167Y62950D01*
X475792Y63117D01*
X474000D01*
G01X474417Y64508D02*
X474167Y64758D01*
X474042Y65050D01*
X474000Y65383D01*
X474083Y65800D01*
X474292Y66092D01*
X474542Y66175D01*
X474792Y66133D01*
X475000Y65967D01*
X475417Y65133D01*
X475708Y64758D01*
X476125Y64508D01*
X476500Y64425D01*
Y66175D01*
G01X474417Y67608D02*
X474167Y67858D01*
X474042Y68150D01*
X474000Y68483D01*
X474083Y68900D01*
X474292Y69192D01*
X474542Y69275D01*
X474792Y69233D01*
X475000Y69067D01*
X475417Y68233D01*
X475708Y67858D01*
X476125Y67608D01*
X476500Y67525D01*
Y69275D01*
G01X441119Y52160D02*
X444119D01*
G01X441119Y61960D02*
X443119D01*
G01X430119Y41160D02*
Y39160D01*
G01X437019Y40260D02*
X442019D01*
Y45260D01*
G01X434124Y95760D02*
X436624D01*
Y97426D01*
G01X434124Y98776D02*
X435916D01*
X436291Y98943D01*
X436541Y99276D01*
X436624Y99693D01*
X436541Y100110D01*
X436291Y100443D01*
X435916Y100610D01*
X434124D01*
G01X436624Y102793D02*
X434124D01*
X434624Y102293D01*
G01X436624D02*
Y103293D01*
G01X445944Y91063D02*
X445694Y91188D01*
X445402Y91271D01*
X445069D01*
X444694Y91146D01*
X444402Y90938D01*
X444194Y90688D01*
X444027Y90271D01*
X443985Y89896D01*
X444069Y89521D01*
X444194Y89271D01*
X444444Y89021D01*
X444735Y88854D01*
X445027Y88771D01*
X445319D01*
X445610Y88854D01*
X445860Y88979D01*
X446069Y89146D01*
G01X447210Y91271D02*
Y89479D01*
X447377Y89104D01*
X447710Y88854D01*
X448127Y88771D01*
X448544Y88854D01*
X448877Y89104D01*
X449044Y89479D01*
Y91271D01*
G01X450435Y90854D02*
X450685Y91104D01*
X450977Y91229D01*
X451310Y91271D01*
X451727Y91188D01*
X452019Y90979D01*
X452102Y90729D01*
X452060Y90479D01*
X451894Y90271D01*
X451060Y89854D01*
X450685Y89563D01*
X450435Y89146D01*
X450352Y88771D01*
X452102D01*
G01X461387Y22966D02*
X461137Y23091D01*
X460845Y23174D01*
X460512D01*
X460137Y23049D01*
X459845Y22841D01*
X459637Y22591D01*
X459470Y22174D01*
X459428Y21799D01*
X459512Y21424D01*
X459637Y21174D01*
X459887Y20924D01*
X460178Y20757D01*
X460470Y20674D01*
X460762D01*
X461053Y20757D01*
X461303Y20882D01*
X461512Y21049D01*
G01X462653Y23174D02*
Y21382D01*
X462820Y21007D01*
X463153Y20757D01*
X463570Y20674D01*
X463987Y20757D01*
X464320Y21007D01*
X464487Y21382D01*
Y23174D01*
G01X466670Y20674D02*
Y23174D01*
X466170Y22674D01*
G01Y20674D02*
X467170D01*
G01X468853Y21174D02*
X469103Y20882D01*
X469437Y20716D01*
X469812Y20674D01*
X470145Y20716D01*
X470478Y20924D01*
X470687Y21174D01*
X470728Y21424D01*
X470645Y21716D01*
X470353Y21924D01*
X470062Y22007D01*
X469687D01*
G01X470062D02*
X470312Y22132D01*
X470520Y22341D01*
X470603Y22591D01*
X470520Y22841D01*
X470312Y23049D01*
X469937Y23174D01*
X469562Y23132D01*
X469187Y22966D01*
G01X485008Y57163D02*
X484758Y57288D01*
X484466Y57371D01*
X484133D01*
X483758Y57246D01*
X483466Y57038D01*
X483258Y56788D01*
X483091Y56371D01*
X483049Y55996D01*
X483133Y55621D01*
X483258Y55371D01*
X483508Y55121D01*
X483799Y54954D01*
X484091Y54871D01*
X484383D01*
X484674Y54954D01*
X484924Y55079D01*
X485133Y55246D01*
G01X486274Y57371D02*
Y55579D01*
X486441Y55204D01*
X486774Y54954D01*
X487191Y54871D01*
X487608Y54954D01*
X487941Y55204D01*
X488108Y55579D01*
Y57371D01*
G01X490291Y54871D02*
Y57371D01*
X489791Y56871D01*
G01Y54871D02*
X490791D01*
G01X493391D02*
Y57371D01*
X492891Y56871D01*
G01Y54871D02*
X493891D01*
G01X498167Y57592D02*
X497917Y57717D01*
X497625Y57800D01*
X497292D01*
X496917Y57675D01*
X496625Y57467D01*
X496417Y57217D01*
X496250Y56800D01*
X496208Y56425D01*
X496292Y56050D01*
X496417Y55800D01*
X496667Y55550D01*
X496958Y55383D01*
X497250Y55300D01*
X497542D01*
X497833Y55383D01*
X498083Y55508D01*
X498292Y55675D01*
G01X499433Y57800D02*
Y56008D01*
X499600Y55633D01*
X499933Y55383D01*
X500350Y55300D01*
X500767Y55383D01*
X501100Y55633D01*
X501267Y56008D01*
Y57800D01*
G01X503450Y55300D02*
Y57800D01*
X502950Y57300D01*
G01Y55300D02*
X503950D01*
G01X505758Y57383D02*
X506008Y57633D01*
X506300Y57758D01*
X506633Y57800D01*
X507050Y57717D01*
X507342Y57508D01*
X507425Y57258D01*
X507383Y57008D01*
X507217Y56800D01*
X506383Y56383D01*
X506008Y56092D01*
X505758Y55675D01*
X505675Y55300D01*
X507425D01*
G01X477305Y77696D02*
X477055Y77821D01*
X476763Y77904D01*
X476430D01*
X476055Y77779D01*
X475763Y77571D01*
X475555Y77321D01*
X475388Y76904D01*
X475346Y76529D01*
X475430Y76154D01*
X475555Y75904D01*
X475805Y75654D01*
X476096Y75487D01*
X476388Y75404D01*
X476680D01*
X476971Y75487D01*
X477221Y75612D01*
X477430Y75779D01*
G01X478571Y77904D02*
Y76112D01*
X478738Y75737D01*
X479071Y75487D01*
X479488Y75404D01*
X479905Y75487D01*
X480238Y75737D01*
X480405Y76112D01*
Y77904D01*
G01X482588Y75404D02*
X482880Y75446D01*
X483213Y75571D01*
X483421Y75779D01*
X483505Y76071D01*
X483421Y76362D01*
X483171Y76612D01*
X482796Y76737D01*
X482380D01*
X482130Y76821D01*
X481921Y77029D01*
X481838Y77321D01*
X481963Y77612D01*
X482255Y77821D01*
X482588Y77904D01*
X482921Y77821D01*
X483213Y77612D01*
X483338Y77321D01*
X483255Y77029D01*
X483046Y76821D01*
X482796Y76737D01*
X482380D01*
X482005Y76612D01*
X481755Y76362D01*
X481671Y76071D01*
X481755Y75779D01*
X481963Y75571D01*
X482296Y75446D01*
X482588Y75404D01*
G01X460217Y43953D02*
X459967Y44078D01*
X459675Y44161D01*
X459342D01*
X458967Y44036D01*
X458675Y43828D01*
X458467Y43578D01*
X458300Y43161D01*
X458258Y42786D01*
X458342Y42411D01*
X458467Y42161D01*
X458717Y41911D01*
X459008Y41744D01*
X459300Y41661D01*
X459592D01*
X459883Y41744D01*
X460133Y41869D01*
X460342Y42036D01*
G01X461483Y44161D02*
Y42369D01*
X461650Y41994D01*
X461983Y41744D01*
X462400Y41661D01*
X462817Y41744D01*
X463150Y41994D01*
X463317Y42369D01*
Y44161D01*
G01X465417Y41661D02*
X465500Y42203D01*
X465625Y42661D01*
X465792Y43078D01*
X466000Y43536D01*
X466333Y44161D01*
X464667D01*
G01X446251Y86648D02*
X446001Y86773D01*
X445709Y86856D01*
X445376D01*
X445001Y86731D01*
X444709Y86523D01*
X444501Y86273D01*
X444334Y85856D01*
X444292Y85481D01*
X444376Y85106D01*
X444501Y84856D01*
X444751Y84606D01*
X445042Y84439D01*
X445334Y84356D01*
X445626D01*
X445917Y84439D01*
X446167Y84564D01*
X446376Y84731D01*
G01X447517Y86856D02*
Y85064D01*
X447684Y84689D01*
X448017Y84439D01*
X448434Y84356D01*
X448851Y84439D01*
X449184Y84689D01*
X449351Y85064D01*
Y86856D01*
G01X450617Y84731D02*
X450867Y84523D01*
X451159Y84398D01*
X451534Y84356D01*
X451909Y84439D01*
X452201Y84606D01*
X452409Y84898D01*
X452451Y85231D01*
X452367Y85564D01*
X452159Y85773D01*
X451867Y85939D01*
X451576Y85981D01*
X451284Y85939D01*
X450909Y85773D01*
X451034Y86856D01*
X452159D01*
G01X470498Y57229D02*
X470248Y57354D01*
X469956Y57437D01*
X469623D01*
X469248Y57312D01*
X468956Y57104D01*
X468748Y56854D01*
X468581Y56437D01*
X468539Y56062D01*
X468623Y55687D01*
X468748Y55437D01*
X468998Y55187D01*
X469289Y55020D01*
X469581Y54937D01*
X469873D01*
X470164Y55020D01*
X470414Y55145D01*
X470623Y55312D01*
G01X471764Y57437D02*
Y55645D01*
X471931Y55270D01*
X472264Y55020D01*
X472681Y54937D01*
X473098Y55020D01*
X473431Y55270D01*
X473598Y55645D01*
Y57437D01*
G01X475781Y54937D02*
Y57437D01*
X475281Y56937D01*
G01Y54937D02*
X476281D01*
G01X478881Y57437D02*
X478548Y57354D01*
X478298Y57145D01*
X478131Y56895D01*
X478006Y56562D01*
X477964Y56187D01*
X478006Y55812D01*
X478131Y55479D01*
X478298Y55229D01*
X478548Y55020D01*
X478881Y54937D01*
X479214Y55020D01*
X479464Y55229D01*
X479631Y55479D01*
X479756Y55812D01*
X479798Y56187D01*
X479756Y56562D01*
X479631Y56895D01*
X479464Y57145D01*
X479214Y57354D01*
X478881Y57437D01*
G01X441445Y27607D02*
X445445D01*
Y35007D01*
G01X458361Y49899D02*
Y52399D01*
X459402D01*
X459736Y52274D01*
X459944Y52107D01*
X460027Y51774D01*
X459944Y51441D01*
X459694Y51232D01*
X459402Y51107D01*
X458361D01*
G01X459402D02*
X460027Y49899D01*
G01X461377Y52399D02*
Y50607D01*
X461544Y50232D01*
X461877Y49982D01*
X462294Y49899D01*
X462711Y49982D01*
X463044Y50232D01*
X463211Y50607D01*
Y52399D01*
G01X465394Y49899D02*
X465686Y49941D01*
X466019Y50066D01*
X466227Y50274D01*
X466311Y50566D01*
X466227Y50857D01*
X465977Y51107D01*
X465602Y51232D01*
X465186D01*
X464936Y51316D01*
X464727Y51524D01*
X464644Y51816D01*
X464769Y52107D01*
X465061Y52316D01*
X465394Y52399D01*
X465727Y52316D01*
X466019Y52107D01*
X466144Y51816D01*
X466061Y51524D01*
X465852Y51316D01*
X465602Y51232D01*
X465186D01*
X464811Y51107D01*
X464561Y50857D01*
X464477Y50566D01*
X464561Y50274D01*
X464769Y50066D01*
X465102Y49941D01*
X465394Y49899D01*
G01X448394Y54538D02*
Y50538D01*
X455794D01*
G01X458373Y45830D02*
Y48330D01*
X459414D01*
X459748Y48205D01*
X459956Y48038D01*
X460039Y47705D01*
X459956Y47372D01*
X459706Y47163D01*
X459414Y47038D01*
X458373D01*
G01X459414D02*
X460039Y45830D01*
G01X461389Y48330D02*
Y46538D01*
X461556Y46163D01*
X461889Y45913D01*
X462306Y45830D01*
X462723Y45913D01*
X463056Y46163D01*
X463223Y46538D01*
Y48330D01*
G01X465323Y45830D02*
X465406Y46372D01*
X465531Y46830D01*
X465698Y47247D01*
X465906Y47705D01*
X466239Y48330D01*
X464573D01*
G01X448406Y50469D02*
Y46469D01*
X455806D01*
G01X478377Y65702D02*
Y68202D01*
X479418D01*
X479752Y68077D01*
X479960Y67910D01*
X480043Y67577D01*
X479960Y67244D01*
X479710Y67035D01*
X479418Y66910D01*
X478377D01*
G01X479418D02*
X480043Y65702D01*
G01X481393Y68202D02*
Y66410D01*
X481560Y66035D01*
X481893Y65785D01*
X482310Y65702D01*
X482727Y65785D01*
X483060Y66035D01*
X483227Y66410D01*
Y68202D01*
G01X484618Y67785D02*
X484868Y68035D01*
X485160Y68160D01*
X485493Y68202D01*
X485910Y68119D01*
X486202Y67910D01*
X486285Y67660D01*
X486243Y67410D01*
X486077Y67202D01*
X485243Y66785D01*
X484868Y66494D01*
X484618Y66077D01*
X484535Y65702D01*
X486285D01*
G01X489010D02*
Y68202D01*
X487468Y66410D01*
X489552D01*
G01X446260Y68541D02*
Y64541D01*
X453660D01*
G01X464635Y28874D02*
X462135D01*
Y29915D01*
X462260Y30249D01*
X462427Y30457D01*
X462760Y30540D01*
X463093Y30457D01*
X463302Y30207D01*
X463427Y29915D01*
Y28874D01*
G01Y29915D02*
X464635Y30540D01*
G01X462135Y31890D02*
X463927D01*
X464302Y32057D01*
X464552Y32390D01*
X464635Y32807D01*
X464552Y33224D01*
X464302Y33557D01*
X463927Y33724D01*
X462135D01*
G01X464260Y34990D02*
X464468Y35240D01*
X464593Y35532D01*
X464635Y35907D01*
X464552Y36282D01*
X464385Y36574D01*
X464093Y36782D01*
X463760Y36824D01*
X463427Y36740D01*
X463218Y36532D01*
X463052Y36240D01*
X463010Y35949D01*
X463052Y35657D01*
X463218Y35282D01*
X462135Y35407D01*
Y36532D01*
G01Y39007D02*
X462218Y38674D01*
X462427Y38424D01*
X462677Y38257D01*
X463010Y38132D01*
X463385Y38090D01*
X463760Y38132D01*
X464093Y38257D01*
X464343Y38424D01*
X464552Y38674D01*
X464635Y39007D01*
X464552Y39340D01*
X464343Y39590D01*
X464093Y39757D01*
X463760Y39882D01*
X463385Y39924D01*
X463010Y39882D01*
X462677Y39757D01*
X462427Y39590D01*
X462218Y39340D01*
X462135Y39007D01*
G01X448400Y35100D02*
X452400D01*
Y42500D01*
G01X468272Y34058D02*
Y36558D01*
X469313D01*
X469647Y36433D01*
X469855Y36266D01*
X469938Y35933D01*
X469855Y35600D01*
X469605Y35391D01*
X469313Y35266D01*
X468272D01*
G01X469313D02*
X469938Y34058D01*
G01X471288Y36558D02*
Y34766D01*
X471455Y34391D01*
X471788Y34141D01*
X472205Y34058D01*
X472622Y34141D01*
X472955Y34391D01*
X473122Y34766D01*
Y36558D01*
G01X474388Y34558D02*
X474638Y34266D01*
X474972Y34100D01*
X475347Y34058D01*
X475680Y34100D01*
X476013Y34308D01*
X476222Y34558D01*
X476263Y34808D01*
X476180Y35100D01*
X475888Y35308D01*
X475597Y35391D01*
X475222D01*
G01X475597D02*
X475847Y35516D01*
X476055Y35725D01*
X476138Y35975D01*
X476055Y36225D01*
X475847Y36433D01*
X475472Y36558D01*
X475097Y36516D01*
X474722Y36350D01*
G01X477488Y34558D02*
X477738Y34266D01*
X478072Y34100D01*
X478447Y34058D01*
X478780Y34100D01*
X479113Y34308D01*
X479322Y34558D01*
X479363Y34808D01*
X479280Y35100D01*
X478988Y35308D01*
X478697Y35391D01*
X478322D01*
G01X478697D02*
X478947Y35516D01*
X479155Y35725D01*
X479238Y35975D01*
X479155Y36225D01*
X478947Y36433D01*
X478572Y36558D01*
X478197Y36516D01*
X477822Y36350D01*
G01X452600Y39100D02*
Y35100D01*
X460000D01*
G01X441418Y35035D02*
X437418D01*
Y27635D01*
G01X452928Y27487D02*
Y31487D01*
X445528D01*
G01X433287Y27608D02*
X437287D01*
Y35008D01*
G01X491425Y71100D02*
X493175Y73600D01*
G01X491425D02*
X493175Y71100D01*
G01X494483Y73600D02*
Y71808D01*
X494650Y71433D01*
X494983Y71183D01*
X495400Y71100D01*
X495817Y71183D01*
X496150Y71433D01*
X496317Y71808D01*
Y73600D01*
G01X498500Y71100D02*
Y73600D01*
X498000Y73100D01*
G01Y71100D02*
X499000D01*
G01X472119Y75192D02*
X455419D01*
Y62992D01*
X472119D01*
Y75192D01*
G01X499595Y74823D02*
Y78823D01*
X502129D01*
G01X501195Y76890D02*
X499595D01*
G01X506662Y74823D02*
Y77490D01*
G01Y77023D02*
X506395Y77290D01*
X505995Y77423D01*
X505529Y77490D01*
X505062Y77356D01*
X504662Y77090D01*
X504395Y76690D01*
X504262Y76156D01*
X504395Y75623D01*
X504662Y75223D01*
X505062Y74956D01*
X505529Y74823D01*
X505995Y74890D01*
X506395Y75090D01*
X506662Y75356D01*
G01X511129Y77156D02*
X510662Y77423D01*
X510262Y77490D01*
X509729Y77356D01*
X509329Y77090D01*
X509062Y76623D01*
X508995Y76156D01*
X509062Y75690D01*
X509329Y75290D01*
X509729Y74956D01*
X510262Y74823D01*
X510729Y74956D01*
X511129Y75223D01*
G01X514662Y78823D02*
Y74823D01*
G01X513729Y77490D02*
X515595D01*
G01X519262Y74823D02*
X518862Y74890D01*
X518462Y75156D01*
X518195Y75623D01*
X518062Y76156D01*
X518195Y76690D01*
X518462Y77156D01*
X518862Y77423D01*
X519262Y77490D01*
X519662Y77423D01*
X520062Y77156D01*
X520329Y76690D01*
X520395Y76156D01*
X520329Y75623D01*
X520062Y75156D01*
X519662Y74890D01*
X519262Y74823D01*
G01X522929D02*
Y77490D01*
G01Y76956D02*
X523262Y77223D01*
X523595Y77423D01*
X524062Y77490D01*
X524395Y77423D01*
X524795Y77223D01*
G01X527062Y73623D02*
X527462Y73490D01*
X527995Y73623D01*
X528329Y73890D01*
X528595Y74223D01*
X528995Y75290D01*
X529862Y77490D01*
G01X527729D02*
X528995Y75290D01*
G01X536862Y78823D02*
X538462D01*
G01X537662D02*
Y74823D01*
G01X536862D02*
X538462D01*
G01X540795D02*
Y78823D01*
X542129D01*
X542662Y78623D01*
X543062Y78356D01*
X543395Y77956D01*
X543662Y77490D01*
X543729Y76823D01*
X543662Y76156D01*
X543395Y75690D01*
X543062Y75290D01*
X542662Y75023D01*
X542129Y74823D01*
X540795D01*
G01X546862Y74690D02*
X546729Y74756D01*
Y74890D01*
X546862Y74956D01*
X546995Y74890D01*
Y74756D01*
X546862Y74690D01*
G01Y76490D02*
X546729Y76556D01*
Y76690D01*
X546862Y76756D01*
X546995Y76690D01*
Y76556D01*
X546862Y76490D01*
G01X550129Y75623D02*
X550462Y75223D01*
X550862Y74956D01*
X551329Y74823D01*
X551862Y74956D01*
X552262Y75223D01*
X552662Y75623D01*
X552795Y76156D01*
Y78823D01*
G01X476193Y82597D02*
X475943Y82722D01*
X475651Y82805D01*
X475318D01*
X474943Y82680D01*
X474651Y82472D01*
X474443Y82222D01*
X474276Y81805D01*
X474234Y81430D01*
X474318Y81055D01*
X474443Y80805D01*
X474693Y80555D01*
X474984Y80388D01*
X475276Y80305D01*
X475568D01*
X475859Y80388D01*
X476109Y80513D01*
X476318Y80680D01*
G01X477584Y81347D02*
X477876Y81638D01*
X478126Y81805D01*
X478459Y81888D01*
X478751Y81805D01*
X478959Y81638D01*
X479126Y81388D01*
X479168Y81097D01*
X479126Y80847D01*
X478959Y80597D01*
X478709Y80388D01*
X478418Y80305D01*
X478084Y80388D01*
X477793Y80638D01*
X477626Y81013D01*
X477584Y81430D01*
X477668Y81972D01*
X477793Y82263D01*
X478001Y82555D01*
X478293Y82763D01*
X478584Y82805D01*
X478876Y82722D01*
X479084Y82513D01*
G01X481476Y80305D02*
Y82805D01*
X480976Y82305D01*
G01Y80305D02*
X481976D01*
G01X453370Y110032D02*
Y107532D01*
G01X452412Y110032D02*
X454328D01*
G01X455637Y107532D02*
Y110032D01*
X456637D01*
X456970Y109907D01*
X457220Y109615D01*
X457303Y109282D01*
X457220Y108949D01*
X457012Y108699D01*
X456637Y108574D01*
X455637D01*
G01X459570Y107532D02*
Y110032D01*
X459070Y109532D01*
G01Y107532D02*
X460070D01*
G01X461878Y108574D02*
X462170Y108865D01*
X462420Y109032D01*
X462753Y109115D01*
X463045Y109032D01*
X463253Y108865D01*
X463420Y108615D01*
X463462Y108324D01*
X463420Y108074D01*
X463253Y107824D01*
X463003Y107615D01*
X462712Y107532D01*
X462378Y107615D01*
X462087Y107865D01*
X461920Y108240D01*
X461878Y108657D01*
X461962Y109199D01*
X462087Y109490D01*
X462295Y109782D01*
X462587Y109990D01*
X462878Y110032D01*
X463170Y109949D01*
X463378Y109740D01*
G01X501949Y158719D02*
X499449D01*
Y159760D01*
X499574Y160094D01*
X499741Y160302D01*
X500074Y160385D01*
X500407Y160302D01*
X500616Y160052D01*
X500741Y159760D01*
Y158719D01*
G01Y159760D02*
X501949Y160385D01*
G01Y162652D02*
X499449D01*
X499949Y162152D01*
G01X501949D02*
Y163152D01*
G01X501574Y164835D02*
X501782Y165085D01*
X501907Y165377D01*
X501949Y165752D01*
X501866Y166127D01*
X501699Y166419D01*
X501407Y166627D01*
X501074Y166669D01*
X500741Y166585D01*
X500532Y166377D01*
X500366Y166085D01*
X500324Y165794D01*
X500366Y165502D01*
X500532Y165127D01*
X499449Y165252D01*
Y166377D01*
G01X501949Y168852D02*
X499449D01*
X499949Y168352D01*
G01X501949D02*
Y169352D01*
G01X505999Y158715D02*
X503499D01*
Y159756D01*
X503624Y160090D01*
X503791Y160298D01*
X504124Y160381D01*
X504457Y160298D01*
X504666Y160048D01*
X504791Y159756D01*
Y158715D01*
G01Y159756D02*
X505999Y160381D01*
G01Y162648D02*
X503499D01*
X503999Y162148D01*
G01X505999D02*
Y163148D01*
G01X505624Y164831D02*
X505832Y165081D01*
X505957Y165373D01*
X505999Y165748D01*
X505916Y166123D01*
X505749Y166415D01*
X505457Y166623D01*
X505124Y166665D01*
X504791Y166581D01*
X504582Y166373D01*
X504416Y166081D01*
X504374Y165790D01*
X504416Y165498D01*
X504582Y165123D01*
X503499Y165248D01*
Y166373D01*
G01Y168848D02*
X503582Y168515D01*
X503791Y168265D01*
X504041Y168098D01*
X504374Y167973D01*
X504749Y167931D01*
X505124Y167973D01*
X505457Y168098D01*
X505707Y168265D01*
X505916Y168515D01*
X505999Y168848D01*
X505916Y169181D01*
X505707Y169431D01*
X505457Y169598D01*
X505124Y169723D01*
X504749Y169765D01*
X504374Y169723D01*
X504041Y169598D01*
X503791Y169431D01*
X503582Y169181D01*
X503499Y168848D01*
G01X497439Y158615D02*
X494939D01*
Y159656D01*
X495064Y159990D01*
X495231Y160198D01*
X495564Y160281D01*
X495897Y160198D01*
X496106Y159948D01*
X496231Y159656D01*
Y158615D01*
G01Y159656D02*
X497439Y160281D01*
G01Y162548D02*
X494939D01*
X495439Y162048D01*
G01X497439D02*
Y163048D01*
G01Y166148D02*
X494939D01*
X496731Y164606D01*
Y166690D01*
G01X497147Y168040D02*
X497356Y168331D01*
X497439Y168665D01*
X497356Y168998D01*
X497106Y169290D01*
X496731Y169498D01*
X496356Y169581D01*
X495897D01*
X495522Y169498D01*
X495189Y169290D01*
X495022Y169040D01*
X494939Y168748D01*
X495022Y168415D01*
X495189Y168165D01*
X495439Y167998D01*
X495772Y167915D01*
X496064Y167998D01*
X496356Y168206D01*
X496522Y168456D01*
X496564Y168748D01*
X496481Y169081D01*
X496272Y169331D01*
X495897Y169581D01*
G01X493369Y158619D02*
X490869D01*
Y159660D01*
X490994Y159994D01*
X491161Y160202D01*
X491494Y160285D01*
X491827Y160202D01*
X492036Y159952D01*
X492161Y159660D01*
Y158619D01*
G01Y159660D02*
X493369Y160285D01*
G01Y162552D02*
X490869D01*
X491369Y162052D01*
G01X493369D02*
Y163052D01*
G01Y166152D02*
X490869D01*
X492661Y164610D01*
Y166694D01*
G01X493369Y168752D02*
X493327Y169044D01*
X493202Y169377D01*
X492994Y169585D01*
X492702Y169669D01*
X492411Y169585D01*
X492161Y169335D01*
X492036Y168960D01*
Y168544D01*
X491952Y168294D01*
X491744Y168085D01*
X491452Y168002D01*
X491161Y168127D01*
X490952Y168419D01*
X490869Y168752D01*
X490952Y169085D01*
X491161Y169377D01*
X491452Y169502D01*
X491744Y169419D01*
X491952Y169210D01*
X492036Y168960D01*
Y168544D01*
X492161Y168169D01*
X492411Y167919D01*
X492702Y167835D01*
X492994Y167919D01*
X493202Y168127D01*
X493327Y168460D01*
X493369Y168752D01*
G01X444260Y104785D02*
X441760D01*
Y105826D01*
X441885Y106160D01*
X442052Y106368D01*
X442385Y106451D01*
X442718Y106368D01*
X442927Y106118D01*
X443052Y105826D01*
Y104785D01*
G01Y105826D02*
X444260Y106451D01*
G01Y108718D02*
X441760D01*
X442260Y108218D01*
G01X444260D02*
Y109218D01*
G01X441760Y111818D02*
X441843Y111485D01*
X442052Y111235D01*
X442302Y111068D01*
X442635Y110943D01*
X443010Y110901D01*
X443385Y110943D01*
X443718Y111068D01*
X443968Y111235D01*
X444177Y111485D01*
X444260Y111818D01*
X444177Y112151D01*
X443968Y112401D01*
X443718Y112568D01*
X443385Y112693D01*
X443010Y112735D01*
X442635Y112693D01*
X442302Y112568D01*
X442052Y112401D01*
X441843Y112151D01*
X441760Y111818D01*
G01X444260Y114918D02*
X444218Y115210D01*
X444093Y115543D01*
X443885Y115751D01*
X443593Y115835D01*
X443302Y115751D01*
X443052Y115501D01*
X442927Y115126D01*
Y114710D01*
X442843Y114460D01*
X442635Y114251D01*
X442343Y114168D01*
X442052Y114293D01*
X441843Y114585D01*
X441760Y114918D01*
X441843Y115251D01*
X442052Y115543D01*
X442343Y115668D01*
X442635Y115585D01*
X442843Y115376D01*
X442927Y115126D01*
Y114710D01*
X443052Y114335D01*
X443302Y114085D01*
X443593Y114001D01*
X443885Y114085D01*
X444093Y114293D01*
X444218Y114626D01*
X444260Y114918D01*
G01X434700Y110600D02*
X438700D01*
Y118000D01*
G01X506775Y127600D02*
Y130100D01*
G01X508525D02*
Y127600D01*
G01Y128850D02*
X506775D01*
G01X509958Y129683D02*
X510208Y129933D01*
X510500Y130058D01*
X510833Y130100D01*
X511250Y130017D01*
X511542Y129808D01*
X511625Y129558D01*
X511583Y129308D01*
X511417Y129100D01*
X510583Y128683D01*
X510208Y128392D01*
X509958Y127975D01*
X509875Y127600D01*
X511625D01*
G01X505500Y178983D02*
X507292D01*
X507667Y179150D01*
X507917Y179483D01*
X508000Y179900D01*
X507917Y180317D01*
X507667Y180650D01*
X507292Y180817D01*
X505500D01*
G01X508000Y183000D02*
X505500D01*
X506000Y182500D01*
G01X508000D02*
Y183500D01*
G01X506958Y185308D02*
X506667Y185600D01*
X506500Y185850D01*
X506417Y186183D01*
X506500Y186475D01*
X506667Y186683D01*
X506917Y186850D01*
X507208Y186892D01*
X507458Y186850D01*
X507708Y186683D01*
X507917Y186433D01*
X508000Y186142D01*
X507917Y185808D01*
X507667Y185517D01*
X507292Y185350D01*
X506875Y185308D01*
X506333Y185392D01*
X506042Y185517D01*
X505750Y185725D01*
X505542Y186017D01*
X505500Y186308D01*
X505583Y186600D01*
X505792Y186808D01*
G01X482070Y212468D02*
Y220268D01*
X494670D01*
Y212468D01*
X482070D01*
G01X485570Y218868D02*
X484970Y218768D01*
X484470Y218268D01*
X484070Y217768D01*
X483870Y217168D01*
X483770Y216368D01*
X483870Y215668D01*
X484070Y214968D01*
X484470Y214468D01*
X484970Y214068D01*
X485570Y213868D01*
X486270Y214068D01*
X486770Y214468D01*
X487070Y214968D01*
X487370Y215668D01*
X487470Y216368D01*
X487370Y217168D01*
X487070Y217768D01*
X486770Y218268D01*
X486270Y218768D01*
X485570Y218868D01*
G01X491170Y213868D02*
Y218868D01*
X490170Y217868D01*
G01Y213868D02*
X492170D01*
G01X469790Y213282D02*
X472290D01*
G01X469790Y212324D02*
Y214240D01*
G01X472290Y215549D02*
X469790D01*
Y216549D01*
X469915Y216882D01*
X470207Y217132D01*
X470540Y217215D01*
X470873Y217132D01*
X471123Y216924D01*
X471248Y216549D01*
Y215549D01*
G01X472290Y219482D02*
X469790D01*
X470290Y218982D01*
G01X472290D02*
Y219982D01*
G01Y222499D02*
X471748Y222582D01*
X471290Y222707D01*
X470873Y222874D01*
X470415Y223082D01*
X469790Y223415D01*
Y221749D01*
G01X505149Y199365D02*
X502649D01*
Y200406D01*
X502774Y200740D01*
X502941Y200948D01*
X503274Y201031D01*
X503607Y200948D01*
X503816Y200698D01*
X503941Y200406D01*
Y199365D01*
G01Y200406D02*
X505149Y201031D01*
G01X504857Y202590D02*
X505066Y202881D01*
X505149Y203215D01*
X505066Y203548D01*
X504816Y203840D01*
X504441Y204048D01*
X504066Y204131D01*
X503607D01*
X503232Y204048D01*
X502899Y203840D01*
X502732Y203590D01*
X502649Y203298D01*
X502732Y202965D01*
X502899Y202715D01*
X503149Y202548D01*
X503482Y202465D01*
X503774Y202548D01*
X504066Y202756D01*
X504232Y203006D01*
X504274Y203298D01*
X504191Y203631D01*
X503982Y203881D01*
X503607Y204131D01*
G01X505149Y206398D02*
X505107Y206690D01*
X504982Y207023D01*
X504774Y207231D01*
X504482Y207315D01*
X504191Y207231D01*
X503941Y206981D01*
X503816Y206606D01*
Y206190D01*
X503732Y205940D01*
X503524Y205731D01*
X503232Y205648D01*
X502941Y205773D01*
X502732Y206065D01*
X502649Y206398D01*
X502732Y206731D01*
X502941Y207023D01*
X503232Y207148D01*
X503524Y207065D01*
X503732Y206856D01*
X503816Y206606D01*
Y206190D01*
X503941Y205815D01*
X504191Y205565D01*
X504482Y205481D01*
X504774Y205565D01*
X504982Y205773D01*
X505107Y206106D01*
X505149Y206398D01*
G01X501019Y199365D02*
X498519D01*
Y200406D01*
X498644Y200740D01*
X498811Y200948D01*
X499144Y201031D01*
X499477Y200948D01*
X499686Y200698D01*
X499811Y200406D01*
Y199365D01*
G01Y200406D02*
X501019Y201031D01*
G01X500727Y202590D02*
X500936Y202881D01*
X501019Y203215D01*
X500936Y203548D01*
X500686Y203840D01*
X500311Y204048D01*
X499936Y204131D01*
X499477D01*
X499102Y204048D01*
X498769Y203840D01*
X498602Y203590D01*
X498519Y203298D01*
X498602Y202965D01*
X498769Y202715D01*
X499019Y202548D01*
X499352Y202465D01*
X499644Y202548D01*
X499936Y202756D01*
X500102Y203006D01*
X500144Y203298D01*
X500061Y203631D01*
X499852Y203881D01*
X499477Y204131D01*
G01X499977Y205606D02*
X499686Y205898D01*
X499519Y206148D01*
X499436Y206481D01*
X499519Y206773D01*
X499686Y206981D01*
X499936Y207148D01*
X500227Y207190D01*
X500477Y207148D01*
X500727Y206981D01*
X500936Y206731D01*
X501019Y206440D01*
X500936Y206106D01*
X500686Y205815D01*
X500311Y205648D01*
X499894Y205606D01*
X499352Y205690D01*
X499061Y205815D01*
X498769Y206023D01*
X498561Y206315D01*
X498519Y206606D01*
X498602Y206898D01*
X498811Y207106D01*
G01X503417Y223100D02*
Y225600D01*
X504458D01*
X504792Y225475D01*
X505000Y225308D01*
X505083Y224975D01*
X505000Y224642D01*
X504750Y224433D01*
X504458Y224308D01*
X503417D01*
G01X504458D02*
X505083Y223100D01*
G01X507350D02*
Y225600D01*
X506850Y225100D01*
G01Y223100D02*
X507850D01*
G01X510450Y225600D02*
X510117Y225517D01*
X509867Y225308D01*
X509700Y225058D01*
X509575Y224725D01*
X509533Y224350D01*
X509575Y223975D01*
X509700Y223642D01*
X509867Y223392D01*
X510117Y223183D01*
X510450Y223100D01*
X510783Y223183D01*
X511033Y223392D01*
X511200Y223642D01*
X511325Y223975D01*
X511367Y224350D01*
X511325Y224725D01*
X511200Y225058D01*
X511033Y225308D01*
X510783Y225517D01*
X510450Y225600D01*
G01X512842Y223392D02*
X513133Y223183D01*
X513467Y223100D01*
X513800Y223183D01*
X514092Y223433D01*
X514300Y223808D01*
X514383Y224183D01*
Y224642D01*
X514300Y225017D01*
X514092Y225350D01*
X513842Y225517D01*
X513550Y225600D01*
X513217Y225517D01*
X512967Y225350D01*
X512800Y225100D01*
X512717Y224767D01*
X512800Y224475D01*
X513008Y224183D01*
X513258Y224017D01*
X513550Y223975D01*
X513883Y224058D01*
X514133Y224267D01*
X514383Y224642D01*
G01X506694Y208056D02*
Y216056D01*
X524294D01*
Y208056D01*
X506694D01*
G01X500217Y197392D02*
X499967Y197517D01*
X499675Y197600D01*
X499342D01*
X498967Y197475D01*
X498675Y197267D01*
X498467Y197017D01*
X498300Y196600D01*
X498258Y196225D01*
X498342Y195850D01*
X498467Y195600D01*
X498717Y195350D01*
X499008Y195183D01*
X499300Y195100D01*
X499592D01*
X499883Y195183D01*
X500133Y195308D01*
X500342Y195475D01*
G01X501483D02*
X501733Y195267D01*
X502025Y195142D01*
X502400Y195100D01*
X502775Y195183D01*
X503067Y195350D01*
X503275Y195642D01*
X503317Y195975D01*
X503233Y196308D01*
X503025Y196517D01*
X502733Y196683D01*
X502442Y196725D01*
X502150Y196683D01*
X501775Y196517D01*
X501900Y197600D01*
X503025D01*
G01X505500Y195100D02*
Y197600D01*
X505000Y197100D01*
G01Y195100D02*
X506000D01*
G01X553019Y173221D02*
Y175721D01*
X554060D01*
X554394Y175596D01*
X554602Y175429D01*
X554685Y175096D01*
X554602Y174763D01*
X554352Y174554D01*
X554060Y174429D01*
X553019D01*
G01X554060D02*
X554685Y173221D01*
G01X556952D02*
Y175721D01*
X556452Y175221D01*
G01Y173221D02*
X557452D01*
G01X560052Y175721D02*
X559719Y175638D01*
X559469Y175429D01*
X559302Y175179D01*
X559177Y174846D01*
X559135Y174471D01*
X559177Y174096D01*
X559302Y173763D01*
X559469Y173513D01*
X559719Y173304D01*
X560052Y173221D01*
X560385Y173304D01*
X560635Y173513D01*
X560802Y173763D01*
X560927Y174096D01*
X560969Y174471D01*
X560927Y174846D01*
X560802Y175179D01*
X560635Y175429D01*
X560385Y175638D01*
X560052Y175721D01*
G01X563152Y173221D02*
Y175721D01*
X562652Y175221D01*
G01Y173221D02*
X563652D01*
G01X539202Y178160D02*
Y174160D01*
X546602D01*
G01X553019Y169191D02*
Y171691D01*
X554060D01*
X554394Y171566D01*
X554602Y171399D01*
X554685Y171066D01*
X554602Y170733D01*
X554352Y170524D01*
X554060Y170399D01*
X553019D01*
G01X554060D02*
X554685Y169191D01*
G01X556952D02*
Y171691D01*
X556452Y171191D01*
G01Y169191D02*
X557452D01*
G01X560052Y171691D02*
X559719Y171608D01*
X559469Y171399D01*
X559302Y171149D01*
X559177Y170816D01*
X559135Y170441D01*
X559177Y170066D01*
X559302Y169733D01*
X559469Y169483D01*
X559719Y169274D01*
X560052Y169191D01*
X560385Y169274D01*
X560635Y169483D01*
X560802Y169733D01*
X560927Y170066D01*
X560969Y170441D01*
X560927Y170816D01*
X560802Y171149D01*
X560635Y171399D01*
X560385Y171608D01*
X560052Y171691D01*
G01X563152D02*
X562819Y171608D01*
X562569Y171399D01*
X562402Y171149D01*
X562277Y170816D01*
X562235Y170441D01*
X562277Y170066D01*
X562402Y169733D01*
X562569Y169483D01*
X562819Y169274D01*
X563152Y169191D01*
X563485Y169274D01*
X563735Y169483D01*
X563902Y169733D01*
X564027Y170066D01*
X564069Y170441D01*
X564027Y170816D01*
X563902Y171149D01*
X563735Y171399D01*
X563485Y171608D01*
X563152Y171691D01*
G01X539202Y174130D02*
Y170130D01*
X546602D01*
G01X524110Y160502D02*
X528110D01*
Y167902D01*
G01X532160Y167898D02*
X528160D01*
Y160498D01*
G01X523600Y167798D02*
X519600D01*
Y160398D01*
G01X515530Y160402D02*
X519530D01*
Y167802D01*
G01X510187Y158675D02*
X507687D01*
Y159716D01*
X507812Y160050D01*
X507979Y160258D01*
X508312Y160341D01*
X508645Y160258D01*
X508854Y160008D01*
X508979Y159716D01*
Y158675D01*
G01Y159716D02*
X510187Y160341D01*
G01Y162608D02*
X507687D01*
X508187Y162108D01*
G01X510187D02*
Y163108D01*
G01Y165625D02*
X509645Y165708D01*
X509187Y165833D01*
X508770Y166000D01*
X508312Y166208D01*
X507687Y166541D01*
Y164875D01*
G01X509687Y167891D02*
X509979Y168141D01*
X510145Y168475D01*
X510187Y168850D01*
X510145Y169183D01*
X509937Y169516D01*
X509687Y169725D01*
X509437Y169766D01*
X509145Y169683D01*
X508937Y169391D01*
X508854Y169100D01*
Y168725D01*
G01Y169100D02*
X508729Y169350D01*
X508520Y169558D01*
X508270Y169641D01*
X508020Y169558D01*
X507812Y169350D01*
X507687Y168975D01*
X507729Y168600D01*
X507895Y168225D01*
G01X536348Y167858D02*
X532348D01*
Y160458D01*
G01X574317Y172292D02*
X574067Y172417D01*
X573775Y172500D01*
X573442D01*
X573067Y172375D01*
X572775Y172167D01*
X572567Y171917D01*
X572400Y171500D01*
X572358Y171125D01*
X572442Y170750D01*
X572567Y170500D01*
X572817Y170250D01*
X573108Y170083D01*
X573400Y170000D01*
X573692D01*
X573983Y170083D01*
X574233Y170208D01*
X574442Y170375D01*
G01X575542Y170000D02*
Y172500D01*
X577458Y170000D01*
Y172500D01*
G01X578808Y172083D02*
X579058Y172333D01*
X579350Y172458D01*
X579683Y172500D01*
X580100Y172417D01*
X580392Y172208D01*
X580475Y171958D01*
X580433Y171708D01*
X580267Y171500D01*
X579433Y171083D01*
X579058Y170792D01*
X578808Y170375D01*
X578725Y170000D01*
X580475D01*
G01X616797Y178624D02*
X564397D01*
Y184224D01*
X533297D01*
Y212824D01*
X564397D01*
Y220024D01*
X616797D01*
Y178624D01*
G01X530926Y178736D02*
X532926D01*
G01X526820Y171802D02*
X531820D01*
Y176802D01*
G01X554977Y226819D02*
X554852Y226569D01*
X554769Y226277D01*
Y225944D01*
X554894Y225569D01*
X555102Y225277D01*
X555352Y225069D01*
X555769Y224902D01*
X556144Y224860D01*
X556519Y224944D01*
X556769Y225069D01*
X557019Y225319D01*
X557186Y225610D01*
X557269Y225902D01*
Y226194D01*
X557186Y226485D01*
X557061Y226735D01*
X556894Y226944D01*
G01X556977Y228294D02*
X557186Y228585D01*
X557269Y228919D01*
X557186Y229252D01*
X556936Y229544D01*
X556561Y229752D01*
X556186Y229835D01*
X555727D01*
X555352Y229752D01*
X555019Y229544D01*
X554852Y229294D01*
X554769Y229002D01*
X554852Y228669D01*
X555019Y228419D01*
X555269Y228252D01*
X555602Y228169D01*
X555894Y228252D01*
X556186Y228460D01*
X556352Y228710D01*
X556394Y229002D01*
X556311Y229335D01*
X556102Y229585D01*
X555727Y229835D01*
G01X554769Y232102D02*
X554852Y231769D01*
X555061Y231519D01*
X555311Y231352D01*
X555644Y231227D01*
X556019Y231185D01*
X556394Y231227D01*
X556727Y231352D01*
X556977Y231519D01*
X557186Y231769D01*
X557269Y232102D01*
X557186Y232435D01*
X556977Y232685D01*
X556727Y232852D01*
X556394Y232977D01*
X556019Y233019D01*
X555644Y232977D01*
X555311Y232852D01*
X555061Y232685D01*
X554852Y232435D01*
X554769Y232102D01*
G01X559407Y226819D02*
X559282Y226569D01*
X559199Y226277D01*
Y225944D01*
X559324Y225569D01*
X559532Y225277D01*
X559782Y225069D01*
X560199Y224902D01*
X560574Y224860D01*
X560949Y224944D01*
X561199Y225069D01*
X561449Y225319D01*
X561616Y225610D01*
X561699Y225902D01*
Y226194D01*
X561616Y226485D01*
X561491Y226735D01*
X561324Y226944D01*
G01X561699Y229002D02*
X561657Y229294D01*
X561532Y229627D01*
X561324Y229835D01*
X561032Y229919D01*
X560741Y229835D01*
X560491Y229585D01*
X560366Y229210D01*
Y228794D01*
X560282Y228544D01*
X560074Y228335D01*
X559782Y228252D01*
X559491Y228377D01*
X559282Y228669D01*
X559199Y229002D01*
X559282Y229335D01*
X559491Y229627D01*
X559782Y229752D01*
X560074Y229669D01*
X560282Y229460D01*
X560366Y229210D01*
Y228794D01*
X560491Y228419D01*
X560741Y228169D01*
X561032Y228085D01*
X561324Y228169D01*
X561532Y228377D01*
X561657Y228710D01*
X561699Y229002D01*
G01X561407Y231394D02*
X561616Y231685D01*
X561699Y232019D01*
X561616Y232352D01*
X561366Y232644D01*
X560991Y232852D01*
X560616Y232935D01*
X560157D01*
X559782Y232852D01*
X559449Y232644D01*
X559282Y232394D01*
X559199Y232102D01*
X559282Y231769D01*
X559449Y231519D01*
X559699Y231352D01*
X560032Y231269D01*
X560324Y231352D01*
X560616Y231560D01*
X560782Y231810D01*
X560824Y232102D01*
X560741Y232435D01*
X560532Y232685D01*
X560157Y232935D01*
G01X563837Y226819D02*
X563712Y226569D01*
X563629Y226277D01*
Y225944D01*
X563754Y225569D01*
X563962Y225277D01*
X564212Y225069D01*
X564629Y224902D01*
X565004Y224860D01*
X565379Y224944D01*
X565629Y225069D01*
X565879Y225319D01*
X566046Y225610D01*
X566129Y225902D01*
Y226194D01*
X566046Y226485D01*
X565921Y226735D01*
X565754Y226944D01*
G01X566129Y229002D02*
X566087Y229294D01*
X565962Y229627D01*
X565754Y229835D01*
X565462Y229919D01*
X565171Y229835D01*
X564921Y229585D01*
X564796Y229210D01*
Y228794D01*
X564712Y228544D01*
X564504Y228335D01*
X564212Y228252D01*
X563921Y228377D01*
X563712Y228669D01*
X563629Y229002D01*
X563712Y229335D01*
X563921Y229627D01*
X564212Y229752D01*
X564504Y229669D01*
X564712Y229460D01*
X564796Y229210D01*
Y228794D01*
X564921Y228419D01*
X565171Y228169D01*
X565462Y228085D01*
X565754Y228169D01*
X565962Y228377D01*
X566087Y228710D01*
X566129Y229002D01*
G01Y232102D02*
X566087Y232394D01*
X565962Y232727D01*
X565754Y232935D01*
X565462Y233019D01*
X565171Y232935D01*
X564921Y232685D01*
X564796Y232310D01*
Y231894D01*
X564712Y231644D01*
X564504Y231435D01*
X564212Y231352D01*
X563921Y231477D01*
X563712Y231769D01*
X563629Y232102D01*
X563712Y232435D01*
X563921Y232727D01*
X564212Y232852D01*
X564504Y232769D01*
X564712Y232560D01*
X564796Y232310D01*
Y231894D01*
X564921Y231519D01*
X565171Y231269D01*
X565462Y231185D01*
X565754Y231269D01*
X565962Y231477D01*
X566087Y231810D01*
X566129Y232102D01*
G01X568308Y227017D02*
X568183Y226767D01*
X568100Y226475D01*
Y226142D01*
X568225Y225767D01*
X568433Y225475D01*
X568683Y225267D01*
X569100Y225100D01*
X569475Y225058D01*
X569850Y225142D01*
X570100Y225267D01*
X570350Y225517D01*
X570517Y225808D01*
X570600Y226100D01*
Y226392D01*
X570517Y226683D01*
X570392Y226933D01*
X570225Y227142D01*
G01Y228283D02*
X570433Y228533D01*
X570558Y228825D01*
X570600Y229200D01*
X570517Y229575D01*
X570350Y229867D01*
X570058Y230075D01*
X569725Y230117D01*
X569392Y230033D01*
X569183Y229825D01*
X569017Y229533D01*
X568975Y229242D01*
X569017Y228950D01*
X569183Y228575D01*
X568100Y228700D01*
Y229825D01*
G01X570600Y232800D02*
X568100D01*
X569892Y231258D01*
Y233342D01*
G01X518810Y207498D02*
X514810D01*
Y200098D01*
G01X514680Y207498D02*
X510680D01*
Y200098D01*
G01X528708Y204217D02*
X528583Y203967D01*
X528500Y203675D01*
Y203342D01*
X528625Y202967D01*
X528833Y202675D01*
X529083Y202467D01*
X529500Y202300D01*
X529875Y202258D01*
X530250Y202342D01*
X530500Y202467D01*
X530750Y202717D01*
X530917Y203008D01*
X531000Y203300D01*
Y203592D01*
X530917Y203883D01*
X530792Y204133D01*
X530625Y204342D01*
G01Y205483D02*
X530833Y205733D01*
X530958Y206025D01*
X531000Y206400D01*
X530917Y206775D01*
X530750Y207067D01*
X530458Y207275D01*
X530125Y207317D01*
X529792Y207233D01*
X529583Y207025D01*
X529417Y206733D01*
X529375Y206442D01*
X529417Y206150D01*
X529583Y205775D01*
X528500Y205900D01*
Y207025D01*
G01X528917Y208708D02*
X528667Y208958D01*
X528542Y209250D01*
X528500Y209583D01*
X528583Y210000D01*
X528792Y210292D01*
X529042Y210375D01*
X529292Y210333D01*
X529500Y210167D01*
X529917Y209333D01*
X530208Y208958D01*
X530625Y208708D01*
X531000Y208625D01*
Y210375D01*
G01X524308Y200717D02*
X524183Y200467D01*
X524100Y200175D01*
Y199842D01*
X524225Y199467D01*
X524433Y199175D01*
X524683Y198967D01*
X525100Y198800D01*
X525475Y198758D01*
X525850Y198842D01*
X526100Y198967D01*
X526350Y199217D01*
X526517Y199508D01*
X526600Y199800D01*
Y200092D01*
X526517Y200383D01*
X526392Y200633D01*
X526225Y200842D01*
G01Y201983D02*
X526433Y202233D01*
X526558Y202525D01*
X526600Y202900D01*
X526517Y203275D01*
X526350Y203567D01*
X526058Y203775D01*
X525725Y203817D01*
X525392Y203733D01*
X525183Y203525D01*
X525017Y203233D01*
X524975Y202942D01*
X525017Y202650D01*
X525183Y202275D01*
X524100Y202400D01*
Y203525D01*
G01X525558Y205208D02*
X525267Y205500D01*
X525100Y205750D01*
X525017Y206083D01*
X525100Y206375D01*
X525267Y206583D01*
X525517Y206750D01*
X525808Y206792D01*
X526058Y206750D01*
X526308Y206583D01*
X526517Y206333D01*
X526600Y206042D01*
X526517Y205708D01*
X526267Y205417D01*
X525892Y205250D01*
X525475Y205208D01*
X524933Y205292D01*
X524642Y205417D01*
X524350Y205625D01*
X524142Y205917D01*
X524100Y206208D01*
X524183Y206500D01*
X524392Y206708D01*
G01X522899Y190708D02*
Y193708D01*
G01X512914Y180676D02*
X510914D01*
G01X517020Y191602D02*
X512020D01*
Y186602D01*
G01X531820D02*
Y191602D01*
X526820D01*
G01X616797Y194524D02*
X612797D01*
Y202524D01*
X616797D01*
G54D12*
G01X545820Y206792D02*
G02I-6450J0D01*
G01Y190256D02*
G02I-6450J0D01*
G01X567474Y206792D02*
G02I-6450J0D01*
G01Y190256D02*
G02I-6450J0D01*
G54D22*
G01X83400Y45600D02*
X87400D01*
G01X87978Y124133D02*
X91978D01*
G01X93068Y124188D02*
X97068D01*
G01X101700Y110500D02*
X97700D01*
G01X96985Y110475D02*
X92985D01*
G01X90217Y179244D02*
X63717D01*
Y177744D01*
G01X90217Y190244D02*
Y179244D01*
G01X63717Y190244D02*
Y170144D01*
G01X97160Y226224D02*
X101160D01*
G01X87548Y226326D02*
X91548D01*
G01X92401Y226211D02*
X96401D01*
G01X82631Y226340D02*
X86631D01*
G01X63717Y190244D02*
X90217D01*
G01X67217Y184744D02*
X63717Y181244D01*
G01X67217Y184744D02*
X63717Y188244D01*
G01X155100Y81600D02*
X159100D01*
G01X168600Y101800D02*
Y105800D01*
G01X165400Y186600D02*
X161400D01*
G01X265544Y172483D02*
Y198983D01*
X264044D01*
G01X276544Y172483D02*
X265544D01*
G01X276544Y198983D02*
X256444D01*
G01X276544D02*
Y172483D01*
G01X271044Y195483D02*
X267544Y198983D01*
G01X271044Y195483D02*
X274544Y198983D01*
G01X429000Y99900D02*
X427000D01*
G01X433600Y18800D02*
X435600D01*
G01X430827Y90710D02*
Y86710D01*
G01X504591Y84103D02*
X506971D01*
G01X504591Y81013D02*
X508491D01*
G01X504591Y87013D02*
Y81013D01*
G01X508491Y87013D02*
X504591D01*
G01X448595Y80376D02*
Y76376D01*
G01X526100Y65200D02*
X525900D01*
G01X521900Y64500D02*
X527100D01*
G01Y63800D02*
X520400D01*
G01X519300Y63100D02*
X527100D01*
G01Y62400D02*
X518400D01*
G01X525900Y61700D02*
X527100D01*
G01X517600D02*
X525900D01*
G01X522700Y61000D02*
X516900D01*
G01X516400Y60300D02*
X521500D01*
G01X520500Y59600D02*
X515900D01*
G01X515500Y58900D02*
X519800D01*
G01X519200Y58200D02*
X515100D01*
G01X514800Y57500D02*
X518800D01*
G01X518400Y56800D02*
X514600D01*
G01X514400Y56100D02*
X518100D01*
G01X517900Y55400D02*
X514200D01*
G01Y54700D02*
X517700D01*
G01X517600Y54000D02*
X514100D01*
G01Y53300D02*
X517600D01*
G01X517700Y52600D02*
X514200D01*
G01X514300Y51900D02*
X517800D01*
G01X518000Y51200D02*
X514300D01*
G01X514500Y50500D02*
X518200D01*
G01X518500Y49800D02*
X514700D01*
G01X514900Y49100D02*
X518800D01*
G01X519300Y48400D02*
X515300D01*
G01X515600Y47700D02*
X519900D01*
G01X520600Y47000D02*
X516000D01*
G01X516600Y46300D02*
X521600D01*
G01X523400Y45600D02*
X517100D01*
G01X517800Y44900D02*
X527100D01*
G01Y44200D02*
X518600D01*
G01X519500Y43500D02*
X527100D01*
G01Y42800D02*
X520800D01*
G01X522600Y42100D02*
X527100D01*
G01Y65100D02*
Y61600D01*
G01X526100Y65200D02*
X527100Y65100D01*
G01X525900Y65200D02*
X526100D01*
G01X523900Y65000D02*
X525900Y65200D01*
G01X521900Y64500D02*
X523900Y65000D01*
G01X520000Y63600D02*
X521900Y64500D01*
G01X518400Y62400D02*
X520000Y63600D01*
G01X516900Y61000D02*
X518400Y62400D01*
G01X515700Y59300D02*
X516900Y61000D01*
G01X514800Y57400D02*
X515700Y59300D01*
G01X514300Y55500D02*
X514800Y57400D01*
G01X514100Y53400D02*
X514300Y55500D01*
G01X514100Y53200D02*
Y53400D01*
G01X514300Y51200D02*
X514100Y53200D01*
G01X514800Y49300D02*
X514300Y51200D01*
G01X515700Y47400D02*
X514800Y49300D01*
G01X516900Y45800D02*
X515700Y47400D01*
G01X518300Y44400D02*
X516900Y45800D01*
G01X519900Y43200D02*
X518300Y44400D01*
G01X521800Y42300D02*
X519900Y43200D01*
G01X523700Y41800D02*
X521800Y42300D01*
G01X525700Y41600D02*
X523700Y41800D01*
G01X526100Y41600D02*
X525700D01*
G01X527100Y41700D02*
X526100Y41600D01*
G01X527100Y45200D02*
Y41700D01*
G01X526300Y45100D02*
X527100Y45200D01*
G01X525700Y45100D02*
X526300D01*
G01X524300Y45300D02*
X525700Y45100D01*
G01X523000Y45700D02*
X524300Y45300D01*
G01X521700Y46200D02*
X523000Y45700D01*
G01X520600Y47000D02*
X521700Y46200D01*
G01X519500Y48100D02*
X520600Y47000D01*
G01X518700Y49200D02*
X519500Y48100D01*
G01X518200Y50500D02*
X518700Y49200D01*
G01X517800Y51800D02*
X518200Y50500D01*
G01X517600Y53200D02*
X517800Y51800D01*
G01X517600Y53400D02*
Y53200D01*
G01X517800Y54800D02*
X517600Y53400D01*
G01X518200Y56200D02*
X517800Y54800D01*
G01X518800Y57500D02*
X518200Y56200D01*
G01X519600Y58700D02*
X518800Y57500D01*
G01X520600Y59700D02*
X519600Y58700D01*
G01X521800Y60500D02*
X520600Y59700D01*
G01X523100Y61200D02*
X521800Y60500D01*
G01X524500Y61500D02*
X523100Y61200D01*
G01X525900Y61700D02*
X524500Y61500D01*
G01X527100Y61600D02*
X525900Y61700D01*
G01X544800Y55000D02*
X536500D01*
G01Y54300D02*
X544800D01*
G01Y53600D02*
X536500D01*
G01Y52900D02*
X544800D01*
G01Y52200D02*
X536500D01*
G01X544800Y55000D02*
Y51800D01*
G01X536500Y55000D02*
X544800D01*
G01X536500Y51800D02*
Y55000D01*
G01X544800Y51800D02*
X536500D01*
G01X546200Y65200D02*
X546000D01*
G01X542000Y64500D02*
X547200D01*
G01Y63800D02*
X540500D01*
G01X539300Y63100D02*
X547200D01*
G01Y62400D02*
X538400D01*
G01X546000Y61700D02*
X547200D01*
G01X537700D02*
X546000D01*
G01X542800Y61000D02*
X537000D01*
G01X536500Y60300D02*
X541600D01*
G01X540600Y59600D02*
X536000D01*
G01X535600Y58900D02*
X539900D01*
G01X539300Y58200D02*
X535200D01*
G01X534900Y57500D02*
X538900D01*
G01X538500Y56800D02*
X534700D01*
G01X534500Y56100D02*
X538100D01*
G01X538000Y55400D02*
X534300D01*
G01Y54700D02*
X537800D01*
G01X537700Y54000D02*
X534200D01*
G01Y53300D02*
X537700D01*
G01X537800Y52600D02*
X534300D01*
G01X534400Y51900D02*
X537900D01*
G01X538100Y51200D02*
X534400D01*
G01X534600Y50500D02*
X538200D01*
G01X538600Y49800D02*
X534800D01*
G01X535000Y49100D02*
X538900D01*
G01X539400Y48400D02*
X535400D01*
G01X535700Y47700D02*
X540000D01*
G01X540600Y47000D02*
X536100D01*
G01X536600Y46300D02*
X541700D01*
G01X543400Y45600D02*
X537200D01*
G01X537900Y44900D02*
X547200D01*
G01Y44200D02*
X538700D01*
G01X539600Y43500D02*
X547200D01*
G01Y42800D02*
X540900D01*
G01X542700Y42100D02*
X547200D01*
G01Y65100D02*
Y61600D01*
G01X546200Y65200D02*
X547200Y65100D01*
G01X546000Y65200D02*
X546200D01*
G01X543900Y65000D02*
X546000Y65200D01*
G01X542000Y64500D02*
X543900Y65000D01*
G01X540100Y63600D02*
X542000Y64500D01*
G01X538400Y62400D02*
X540100Y63600D01*
G01X537000Y61000D02*
X538400Y62400D01*
G01X535800Y59300D02*
X537000Y61000D01*
G01X534900Y57400D02*
X535800Y59300D01*
G01X534400Y55500D02*
X534900Y57400D01*
G01X534200Y53400D02*
X534400Y55500D01*
G01X534200Y53200D02*
Y53400D01*
G01X534400Y51200D02*
X534200Y53200D01*
G01X534900Y49300D02*
X534400Y51200D01*
G01X535800Y47400D02*
X534900Y49300D01*
G01X536900Y45800D02*
X535800Y47400D01*
G01X538400Y44400D02*
X536900Y45800D01*
G01X540000Y43200D02*
X538400Y44400D01*
G01X541900Y42300D02*
X540000Y43200D01*
G01X543800Y41800D02*
X541900Y42300D01*
G01X545800Y41600D02*
X543800Y41800D01*
G01X546200Y41600D02*
X545800D01*
G01X547200Y41700D02*
X546200Y41600D01*
G01X547200Y45200D02*
Y41700D01*
G01X546400Y45100D02*
X547200Y45200D01*
G01X545800Y45100D02*
X546400D01*
G01X544400Y45300D02*
X545800Y45100D01*
G01X543000Y45700D02*
X544400Y45300D01*
G01X541800Y46200D02*
X543000Y45700D01*
G01X540600Y47000D02*
X541800Y46200D01*
G01X539600Y48100D02*
X540600Y47000D01*
G01X538800Y49200D02*
X539600Y48100D01*
G01X538200Y50500D02*
X538800Y49200D01*
G01X537900Y51800D02*
X538200Y50500D01*
G01X537700Y53200D02*
X537900Y51800D01*
G01X537700Y53400D02*
Y53200D01*
G01X537900Y54800D02*
X537700Y53400D01*
G01X538200Y56200D02*
X537900Y54800D01*
G01X538900Y57500D02*
X538200Y56200D01*
G01X539700Y58700D02*
X538900Y57500D01*
G01X540700Y59700D02*
X539700Y58700D01*
G01X541900Y60500D02*
X540700Y59700D01*
G01X543200Y61200D02*
X541900Y60500D01*
G01X544600Y61500D02*
X543200Y61200D01*
G01X546000Y61700D02*
X544600Y61500D01*
G01X547200Y61600D02*
X546000Y61700D01*
G01X535797Y94707D02*
Y91293D01*
X535773Y91269D01*
G01X535546Y94719D02*
X535534Y94731D01*
G01X540861Y81563D02*
X540591Y82103D01*
G01X541141Y81283D02*
X540861Y81563D01*
G01X541961Y81013D02*
X541141Y81283D01*
G01X542811Y81013D02*
X541961D01*
G01X543631Y81283D02*
X542811Y81013D01*
G01X544181Y81833D02*
X543631Y81283D01*
G01X544491Y82653D02*
X544181Y81833D01*
G01X544491Y83283D02*
Y82653D01*
G01X544181Y84103D02*
X544491Y83283D01*
G01X543911Y84373D02*
X544181Y84103D01*
G01X543361Y84653D02*
X543911Y84373D01*
G01X542501Y84653D02*
X543361D01*
G01X544181Y86923D02*
X542501Y84653D01*
G01X541141Y86923D02*
X544181D01*
G01X537091D02*
X535961D01*
G01X537911Y86653D02*
X537091Y86923D01*
G01X538181Y86103D02*
X537911Y86653D01*
G01X538181Y85563D02*
Y86103D01*
G01X537911Y84923D02*
X538181Y85563D01*
G01X537361Y84653D02*
X537911Y84923D01*
G01X536231Y84373D02*
X537361Y84653D01*
G01X535411Y84103D02*
X536231Y84373D01*
G01X534861Y83563D02*
X535411Y84103D01*
G01X534591Y83013D02*
X534861Y83563D01*
G01X534591Y82103D02*
Y83013D01*
G01X534861Y81563D02*
X534591Y82103D01*
G01X535141Y81283D02*
X534861Y81563D01*
G01X535961Y81013D02*
X535141Y81283D01*
G01X537091Y81013D02*
X535961D01*
G01X537911Y81283D02*
X537091Y81013D01*
G01X538181Y81563D02*
X537911Y81283D01*
G01X538491Y82103D02*
X538181Y81563D01*
G01X538491Y83013D02*
Y82103D01*
G01X538181Y83563D02*
X538491Y83013D01*
G01X537631Y84103D02*
X538181Y83563D01*
G01X536811Y84373D02*
X537631Y84103D01*
G01X535681Y84653D02*
X536811Y84373D01*
G01X535141Y84923D02*
X535681Y84653D01*
G01X534861Y85563D02*
X535141Y84923D01*
G01X534861Y86103D02*
Y85563D01*
G01X535141Y86653D02*
X534861Y86103D01*
G01X535961Y86923D02*
X535141Y86653D01*
G01X528591Y83013D02*
X532491D01*
G01X531161Y86923D02*
X528591Y83013D01*
G01X531161Y86923D02*
Y81013D01*
G01X522861Y81563D02*
X522591Y82103D01*
G01X523141Y81283D02*
X522861Y81563D01*
G01X523961Y81013D02*
X523141Y81283D01*
G01X524771Y81013D02*
X523961D01*
G01X525631Y81283D02*
X524771Y81013D01*
G01X526181Y81833D02*
X525631Y81283D01*
G01X526491Y82653D02*
X526181Y81833D01*
G01X526491Y83283D02*
Y82653D01*
G01X526181Y84103D02*
X526491Y83283D01*
G01X525631Y84653D02*
X526181Y84103D01*
G01X524771Y84923D02*
X525631Y84653D01*
G01X523961Y84923D02*
X524771D01*
G01X523141Y84653D02*
X523961Y84923D01*
G01X522861Y84373D02*
X523141Y84653D01*
G01Y86923D02*
X522861Y84373D01*
G01X525911Y86923D02*
X523141D01*
G01X516591Y83013D02*
X520491D01*
G01X519161Y86923D02*
X516591Y83013D01*
G01X519161Y86923D02*
Y81013D01*
G01X512891Y86923D02*
Y81013D01*
G01X512421Y86103D02*
X512891Y86923D01*
G01X512111Y85833D02*
X512421Y86103D01*
G54D13*
G01X108000Y55600D02*
X105150D01*
Y58300D01*
G01X125500Y69600D02*
X128350D01*
Y66900D01*
G01X468269Y75592D02*
X472469D01*
Y71692D01*
G01X564047Y220374D02*
X617147D01*
G54D14*
G01X345538Y32869D02*
X338538D01*
G01X348738Y69869D02*
X341738D01*
G54D15*
G01X14916Y0D02*
X45625D01*
G01X0Y81561D02*
Y50852D01*
G01Y186482D02*
Y217191D01*
G01X10964Y332539D02*
X41673D01*
G01X51397Y249862D02*
X93906D01*
G01X51397Y241988D02*
X93906D01*
G01X57087Y442487D02*
Y473195D01*
G01X420300Y-21500D02*
G03I-9100J0D01*
G01X558661Y49363D02*
Y18655D01*
G01X604784Y159311D02*
X574075D01*
G01X564353Y249862D02*
X521844D01*
G01X564353Y241988D02*
X521844D01*
G01X600832Y491850D02*
X570123D01*
G01X615748Y305368D02*
Y274659D01*
G01Y440998D02*
Y410289D01*
G54D16*
G01X506500Y38900D02*
G03I-10900J0D01*
G54D17*
G01X148148Y-2342D02*
Y1058D01*
G54D18*
G01X511370Y13790D02*
X510710D01*
G01X510810Y13880D02*
X511470D01*
G01X511560Y13990D02*
X510910D01*
G01X511010Y14080D02*
X511660D01*
G01X511760Y14190D02*
X511100D01*
G01X511200Y14290D02*
X511850D01*
G01X511950Y14380D02*
X511300D01*
G01X511390Y14490D02*
X512050D01*
G01X512140Y14580D02*
X511490D01*
G01X511580Y14690D02*
X512240D01*
G01X512340Y14790D02*
X511680D01*
G01X511780Y14880D02*
X512430D01*
G01X512530Y14990D02*
X511885D01*
G01X511880D02*
X511930D01*
G01X511970Y15080D02*
X512010D01*
G01X511970D02*
X512620D01*
G01X512720Y15190D02*
X512070D01*
G01X512170Y15290D02*
X512820D01*
G01X512920Y15380D02*
X512260D01*
G01X512360Y15490D02*
X513010D01*
G01X513110Y15580D02*
X512450D01*
G01X512550Y15690D02*
X513210D01*
G01X513300Y15790D02*
X512650D01*
G01X512750Y15880D02*
X513400D01*
G01X513490Y15990D02*
X512840D01*
G01X512940Y16080D02*
X513590D01*
G01X513690Y16190D02*
X513030D01*
G01X513130Y16290D02*
X513790D01*
G01X513880Y16380D02*
X513230D01*
G01X513320Y16490D02*
X513980D01*
G01X514170Y16690D02*
X513520D01*
G01X513710Y16880D02*
X514360D01*
G01X515310Y19490D02*
X514840D01*
G01X514860Y19290D02*
X515330D01*
G01X515350Y19080D02*
X514880D01*
G01X514900Y18880D02*
X515370D01*
G01X515410Y18790D02*
X514910D01*
G01X514920Y18140D02*
X514820Y18030D01*
G01X514950Y18210D02*
X514920Y18140D01*
G01X514770Y17990D02*
X515460D01*
G01Y17790D02*
X514580D01*
G01X514390Y17580D02*
X515480D01*
G01X514840Y17380D02*
X514190D01*
G01X514100Y17290D02*
X514750D01*
G01X514650Y17190D02*
X514000D01*
G01X513900Y17080D02*
X514560D01*
G01X514460Y16990D02*
X513810D01*
G01X513620Y16790D02*
X514270D01*
G01X514070Y16580D02*
X513420D01*
G01X514950Y18270D02*
Y18210D01*
G01X514820Y19730D02*
X514950Y18270D01*
G01X514940Y18190D02*
X515620D01*
G01X515470Y18010D02*
X515450Y17940D01*
G01X515520Y18090D02*
X515470Y18010D01*
G01X515450Y17880D02*
X514680D01*
G01X514490Y17690D02*
X515470D01*
G01X515490Y17380D02*
X514990D01*
G01X514960Y17420D02*
X514860Y17400D01*
G01X515230Y14980D02*
X515340D01*
G01X515230Y14990D02*
Y14980D01*
G01X515030Y17340D02*
X515230Y14990D01*
G01X514960Y17420D02*
X515030Y17340D01*
G01X515330Y15080D02*
X515220D01*
G01X515225D02*
X520820D01*
G01X520885Y14990D02*
X515230D01*
G01X515470Y13940D02*
X516360D01*
G01X515430Y13980D02*
X515470Y13940D01*
G01X515430Y14660D02*
Y13980D01*
G01X515400Y14730D02*
X515430Y14660D01*
G01X515250Y14890D02*
X515400Y14730D01*
G01X515240Y14910D02*
X515250Y14890D01*
G01X515230Y14970D02*
X515240Y14910D01*
G01X516400Y13990D02*
X515430D01*
G01Y14190D02*
X516400D01*
G01Y14380D02*
X515430D01*
G01Y14580D02*
X516400D01*
G01X515680Y15290D02*
X515210D01*
G01X515190Y15380D02*
X515660D01*
G01X515650Y15580D02*
X515180D01*
G01X515160Y15790D02*
X515630D01*
G01X515610Y15990D02*
X515140D01*
G01X515130Y16190D02*
X515600D01*
G01X515580Y16380D02*
X515110D01*
G01X515090Y16580D02*
X515560D01*
G01X515550Y16790D02*
X515080D01*
G01X515060Y16990D02*
X515530D01*
G01X515510Y17190D02*
X515050D01*
G01X514940Y18380D02*
X515810D01*
G01X516000Y18580D02*
X514920D01*
G01X514890Y18990D02*
X515360D01*
G01X515370Y18840D02*
X514920Y24130D01*
G01X515310Y19580D02*
X514840D01*
G01X514850Y19380D02*
X515320D01*
G01X515340Y19190D02*
X514870D01*
G01X515440Y18750D02*
X515540Y18780D01*
G01X515370Y18840D02*
X515440Y18750D01*
G01X515350Y14790D02*
X521130D01*
G01X515670Y15360D02*
X515450Y17940D01*
G01X515670Y15290D02*
Y15360D01*
G01X515770Y15200D02*
X515670Y15290D01*
G01X519870Y15200D02*
X515770D01*
G01X515520Y18080D02*
X514870D01*
G01X514950Y18290D02*
X515710D01*
G01X515530Y18090D02*
X515520D01*
G01X515530Y18100D02*
Y18090D01*
G01Y18100D02*
X518120Y20790D01*
G01X516660Y19940D02*
X515540Y18780D01*
G01X515550Y18790D02*
X516190D01*
G01X516100Y18690D02*
X514920D01*
G01X514930Y18490D02*
X515910D01*
G01X515650Y18880D02*
X516290D01*
G01X516390Y18990D02*
X515750D01*
G01X515840Y19080D02*
X516490D01*
G01X516580Y19190D02*
X515940D01*
G01X516030Y19290D02*
X516680D01*
G01X516770Y19380D02*
X516130D01*
G01X516230Y19490D02*
X516870D01*
G01X516970Y19580D02*
X516320D01*
G01X515490Y17490D02*
X514290D01*
G01X515030Y17290D02*
X515500D01*
G01X515520Y17080D02*
X515050D01*
G01X515070Y16880D02*
X515540D01*
G01X515550Y16690D02*
X515080D01*
G01X515100Y16490D02*
X515570D01*
G01X515590Y16290D02*
X515120D01*
G01X515140Y16080D02*
X515600D01*
G01X515620Y15880D02*
X515160D01*
G01X515170Y15690D02*
X515640D01*
G01X515660Y15490D02*
X515190D01*
G01X515420Y14690D02*
X516470D01*
G01X516400Y13980D02*
X516360Y13940D01*
G01X516400Y14620D02*
Y13980D01*
G01X516500Y14720D02*
X516400Y14620D01*
G01Y14080D02*
X515430D01*
G01Y14290D02*
X516400D01*
G01Y14490D02*
X515430D01*
G01X519970Y15670D02*
Y15680D01*
G01X519960Y15600D02*
X519970Y15670D01*
G01X519960Y15340D02*
Y15600D01*
G01X519970Y15320D02*
X519960Y15340D01*
G01X519870Y15200D02*
X519970Y15320D01*
G01Y15690D02*
X520740D01*
G01X520700Y15490D02*
X519960D01*
G01X519940Y15290D02*
X520740D01*
G01X521280Y18220D02*
X518580Y21120D01*
G01X518270Y20790D02*
X519950Y18970D01*
G01X519940Y18990D02*
X520570D01*
G01X520380Y19190D02*
X519750D01*
G01X519570Y19380D02*
X520200D01*
G01X520010Y19580D02*
X519380D01*
G01X520100Y19490D02*
X519470D01*
G01X519660Y19290D02*
X520290D01*
G01X520470Y19080D02*
X519840D01*
G01X520030Y18880D02*
X520660D01*
G01X520750Y18790D02*
X520120D01*
G01X520210Y18690D02*
X520850D01*
G01X520940Y18580D02*
X520310D01*
G01X520400Y18490D02*
X521030D01*
G01X521220Y18290D02*
X520590D01*
G01X520770Y18080D02*
X521910D01*
G01X521900Y17990D02*
X520870D01*
G01X520010Y15860D02*
X519970Y15680D01*
G01X520010Y15870D02*
Y15860D01*
G01X520120Y16180D02*
X520010Y15870D01*
G01X520130Y16190D02*
X520120Y16180D01*
G01X520340Y16500D02*
X520130Y16190D01*
G01X520350Y16510D02*
X520340Y16500D01*
G01X520590Y16730D02*
X520350Y16510D01*
G01X520600Y16730D02*
X520590D01*
G01X520720Y16810D02*
X520600Y16730D01*
G01X520730Y16820D02*
X520720Y16810D01*
G01X520790Y16850D02*
X520730Y16820D01*
G01X520950Y16920D02*
X520790Y16850D01*
G01X519960Y15580D02*
X520720D01*
G01X520760Y15190D02*
X515210D01*
G01X520750Y15210D02*
X520760Y15190D01*
G01X520700Y15470D02*
X520750Y15210D01*
G01X520700Y15480D02*
Y15470D01*
G01Y15500D02*
Y15480D01*
G01X515250Y14880D02*
X520990D01*
G01X520910Y14950D02*
X520850Y15040D01*
G01X520920Y14940D02*
X520910Y14950D01*
G01X520930Y14930D02*
X520920Y14940D01*
G01X520770Y15180D02*
X520760Y15190D01*
G01X520850Y15050D02*
X520770Y15180D01*
G01X520720Y15380D02*
X519960D01*
G01X519990Y15790D02*
X520760D01*
G01X520750Y15760D02*
X520700Y15500D01*
G01X520760Y15780D02*
X520750Y15760D01*
G01X520980Y15510D02*
X520990Y15530D01*
G01X520930Y16040D02*
X521150Y16200D01*
G01X520920Y16030D02*
X520930Y16040D01*
G01X520910Y16010D02*
X520920Y16030D01*
G01X520770Y15800D02*
X520910Y16010D01*
G01X520760Y15780D02*
X520770Y15800D01*
G01X520990Y16080D02*
X520090D01*
G01X520050Y15990D02*
X520890D01*
G01X520820Y15880D02*
X520010D01*
G01X520190Y16290D02*
X521450D01*
G01X520860Y16880D02*
X522530D01*
G01X522620Y16790D02*
X520680D01*
G01X520440Y16580D02*
X522810D01*
G01X522990Y16380D02*
X520270D01*
G01X520850Y14990D02*
X520890D01*
G01X520930Y14930D02*
X521150Y14770D01*
G01X520720Y14190D02*
X522270D01*
G01X522430Y14290D02*
X520540D01*
G01X520100Y14720D02*
X516500D01*
G01X520180Y14690D02*
X520100Y14720D01*
G01X520190Y14680D02*
X520180Y14690D01*
G01X520190Y14670D02*
Y14680D01*
G01X520230Y14600D02*
X520190Y14670D01*
G01X520240Y14600D02*
X520230D01*
G01X520250Y14590D02*
X520240Y14600D01*
G01X520320Y14490D02*
X520250Y14590D01*
G01X520330Y14480D02*
X520320Y14490D01*
G01X520560Y14260D02*
X520330Y14480D01*
G01Y14490D02*
X522670D01*
G01X520580Y14250D02*
X520560Y14260D01*
G01X521380Y13950D02*
X521720Y13960D01*
G01X521370Y13950D02*
X521380D01*
G01X521360D02*
X521370D01*
G01X521200Y13970D02*
X521360Y13950D01*
G01X521180Y13970D02*
X521200D01*
G01X520580Y14250D02*
X521180Y13970D01*
G01X521830Y13990D02*
X521160D01*
G01Y14760D02*
X521150Y14770D01*
G01X521180Y14760D02*
X521160D01*
G01X521350Y14700D02*
X521180Y14760D01*
G01X521570Y14690D02*
X521590D01*
G01X521440D02*
X521570D01*
G01X521370Y14700D02*
X521440Y14690D01*
G01X521350Y14700D02*
X521370D01*
G01X521010Y15320D02*
X520980Y15510D01*
G01X521020Y15290D02*
X521010Y15320D01*
G01X521190Y15070D02*
X521020Y15290D01*
G01X521210Y15060D02*
X521190Y15070D01*
G01X521380Y14980D02*
X521210Y15060D01*
G01X521390Y14980D02*
X521380D01*
G01X521430Y14970D02*
X521390Y14980D01*
G01X521490Y14970D02*
X521430D01*
G01X521510D02*
X521490D01*
G01X521540Y16000D02*
X521550D01*
G01X521450D02*
X521540D01*
G01X521430Y15990D02*
X521450Y16000D01*
G01X521120Y15830D02*
X521430Y15990D01*
G01X521100Y15810D02*
X521120Y15830D01*
G01X520990Y15530D02*
X521100Y15810D01*
G01X521160Y16210D02*
X521150Y16200D01*
G01X521180Y16210D02*
X521160D01*
G01X521350Y16270D02*
X521180Y16210D01*
G01X521370Y16270D02*
X521350D01*
G01X521440Y16280D02*
X521370Y16270D01*
G01X521460Y16290D02*
X521440Y16280D01*
G01X521520Y16290D02*
X521460D01*
G01X521550Y16280D02*
X521520Y16290D01*
G01X521130Y16190D02*
X520130D01*
G01X521040Y15670D02*
X521980D01*
G01X522000Y15470D02*
X520990D01*
G01X521040Y15270D02*
X521950D01*
G01X521770Y15070D02*
X521200D01*
G01X521510Y14970D02*
X521640Y14990D01*
G01X521840Y15860D02*
X521190D01*
G01X521590Y16280D02*
X521790Y16230D01*
G01X521550Y16280D02*
X521590D01*
G01X521040Y16950D02*
X520950Y16920D01*
G01X521050Y16960D02*
X521040Y16950D01*
G01X521190Y16990D02*
X521050Y16960D01*
G01X521270Y17010D02*
X521190Y16990D01*
G01X521050Y17790D02*
X519950Y18970D01*
G01X521310Y17510D02*
X521050Y17790D01*
G01X521340Y17460D02*
X521310Y17510D01*
G01X521370Y17310D02*
X521340Y17460D01*
G01X521380Y17290D02*
X521370Y17310D01*
G01X521380Y17270D02*
Y17290D01*
G01X521360Y17100D02*
X521380Y17270D01*
G01X521360Y17090D02*
Y17100D01*
G01X521270Y17010D02*
X521360Y17090D01*
G01X520490Y18380D02*
X521130D01*
G01X521450Y18280D02*
X521960Y24510D01*
G01X521390Y18200D02*
X521450Y18280D01*
G01X521280Y18220D02*
X521390Y18200D01*
G01X521550Y19490D02*
X522020D01*
G01X522010Y19290D02*
X521540D01*
G01X521520Y19080D02*
X521990D01*
G01X521970Y18880D02*
X521510D01*
G01X521490Y18690D02*
X521950D01*
G01X521940Y18490D02*
X521470D01*
G01X521450Y18290D02*
X521920D01*
G01X521880Y17790D02*
X521050D01*
G01X521240Y17580D02*
X521880D01*
G01X522060Y17380D02*
X521360D01*
G01X521370Y17190D02*
X522250D01*
G01X522030Y19580D02*
X521560D01*
G01X521550Y19380D02*
X522010D01*
G01X522000Y19190D02*
X521530D01*
G01X521510Y18990D02*
X521980D01*
G01X521960Y18790D02*
X521500D01*
G01X521480Y18580D02*
X521950D01*
G01X521930Y18380D02*
X521460D01*
G01X521920Y18190D02*
X520680D01*
G01X520960Y17880D02*
X521890D01*
G01X521880Y17690D02*
X521150D01*
G01X521320Y17490D02*
X521960D01*
G01X521900Y17550D02*
X522860Y16530D01*
G01X523180Y16190D02*
X521850D01*
G01X521830Y16210D02*
X521790Y16230D01*
G01X521830Y16210D02*
X522140Y15950D01*
G01X521910Y15770D02*
X521080D01*
G01X521000Y15570D02*
X521990D01*
G01X521800Y15900D02*
X521550Y16000D01*
G01X521820Y15890D02*
X521800Y15900D01*
G01X521970Y15690D02*
X521820Y15890D01*
G01X521980Y15660D02*
X521970Y15690D01*
G01X521640Y15970D02*
X521370D01*
G01X521660Y14990D02*
X521640D01*
G01X521880Y15130D02*
X521660Y14990D01*
G01X521890Y15150D02*
X521880Y15130D01*
G01X522000Y15380D02*
X521890Y15150D01*
G01X522010Y15400D02*
X522000Y15380D01*
G01X521980Y15660D02*
X522010Y15400D01*
G01X521850Y14790D02*
X522870D01*
G01X521730Y13960D02*
X521720D01*
G01X522020Y14030D02*
X521730Y13960D01*
G01X522030Y14040D02*
X522020Y14030D01*
G01X522540Y14350D02*
X522030Y14040D01*
G01X521790Y14740D02*
X521830Y14760D01*
G01X521590Y14690D02*
X521790Y14740D01*
G01X521900Y15170D02*
X521120D01*
G01X521000Y15360D02*
X522000D01*
G01X521890Y17570D02*
X521870Y17640D01*
G01X521900Y17560D02*
X521890Y17570D01*
G01X521900Y17550D02*
Y17560D01*
G01X522440Y24570D02*
X521870Y17640D01*
G01X522150Y17290D02*
X521380D01*
G01X521350Y17080D02*
X522340D01*
G01X522430Y16990D02*
X521160D01*
G01X520550Y16690D02*
X522710D01*
G01X522900Y16490D02*
X520330D01*
G01X520180Y14690D02*
X522810D01*
G01X522630Y14440D02*
X522540Y14350D01*
G01X522690Y14510D02*
X522630Y14440D01*
G01X522820Y14700D02*
X522690Y14510D01*
G01X522580Y14380D02*
X520430D01*
G01X520250Y14580D02*
X522740D01*
G01X522940Y14950D02*
X523000Y15120D01*
G01X522900Y14850D02*
X522940Y14950D01*
G01X522900Y14840D02*
Y14850D01*
G01X522830Y14710D02*
X522900Y14840D01*
G01X522820Y14700D02*
X522830Y14710D01*
G01X522990Y15080D02*
X522175D01*
G01X522180D02*
X522240D01*
G01X522140Y15020D02*
X521830Y14760D01*
G01X522170Y15070D02*
X522140Y15020D01*
G01X521970Y14880D02*
X522920D01*
G01X522950Y14990D02*
X522160D01*
G01X522920D02*
X522950D01*
G01X522170Y15900D02*
X522140Y15950D01*
G01X522290Y15510D02*
X522170Y15900D01*
G01X522290Y15450D02*
Y15510D01*
G01X522170Y15070D02*
X522290Y15450D01*
G01X522100Y15990D02*
X523360D01*
G01X523550Y15790D02*
X522210D01*
G01X522270Y15580D02*
X523730D01*
G01X523030Y15380D02*
X522270D01*
G01X522210Y15190D02*
X523010D01*
G01X522100Y14080D02*
X520940D01*
G01X523080Y16290D02*
X521530D01*
G01X521970Y16080D02*
X523270D01*
G01X523450Y15880D02*
X522180D01*
G01X522230Y15690D02*
X523640D01*
G01X523830Y15490D02*
X523140D01*
G01X523000Y15140D02*
Y15120D01*
G01X523040Y15410D02*
X523000Y15140D01*
G01X523100Y15490D02*
X523040Y15410D01*
G01X523020Y15290D02*
X522240D01*
G01X523100Y15490D02*
X523210Y15470D01*
G01X522290Y15490D02*
X523100D01*
G01X523290Y15380D02*
X523920D01*
G01X524010Y15290D02*
X523380D01*
G01X523470Y15190D02*
X524110D01*
G01X524160Y15080D02*
X524200D01*
G01X524210D02*
X523570D01*
G01X523660Y14990D02*
X524295D01*
G01X524290D02*
X524240D01*
G01X524395Y14880D02*
X523750D01*
G01X523840Y14790D02*
X524480D01*
G01X524570Y14690D02*
X523935D01*
G01X524035Y14580D02*
X524670D01*
G01X524760Y14490D02*
X524120D01*
G01X524225Y14380D02*
X524850D01*
G01X524950Y14290D02*
X524310D01*
G01X524400Y14190D02*
X525040D01*
G01X525130Y14080D02*
X524490D01*
G01X524580Y13990D02*
X525230D01*
G01X525410Y13790D02*
X524770D01*
G01X524680Y13880D02*
X525320D01*
G01X525500Y13690D02*
X524860D01*
G01X524960Y13580D02*
X525600D01*
G01X525690Y13490D02*
X525050D01*
G01X525140Y13380D02*
X525780D01*
G01X525880Y13290D02*
X525230D01*
G01X525330Y13190D02*
X525970D01*
G01X526060Y13080D02*
X525420D01*
G01X525510Y12990D02*
X526160D01*
G01X526250Y12880D02*
X525610D01*
G01X525700Y12790D02*
X526340D01*
G01X526530Y12580D02*
X525890D01*
G01X526070Y12380D02*
X526680D01*
G01X526670Y12440D02*
X522860Y16530D01*
G01X526340Y12100D02*
X526360Y12080D01*
G01X523210Y15470D02*
X526340Y12100D01*
G01X526260Y12190D02*
X526480D01*
G01X509400Y12420D02*
X514820Y18030D01*
G01X509370Y12390D02*
X509400Y12420D01*
G01X509380Y12370D02*
X509370Y12390D01*
G01X509690Y12100D02*
X509380Y12370D01*
G01X509720Y12090D02*
X509690Y12100D01*
G01X509740D02*
X509720Y12090D01*
G01X514860Y17400D02*
X509740Y12100D01*
G01X509820Y12190D02*
X509590D01*
G01X509470Y12290D02*
X509920D01*
G01X510020Y12380D02*
X509370D01*
G01X509460Y12490D02*
X510120D01*
G01X510210Y12580D02*
X509560D01*
G01X509650Y12690D02*
X510310D01*
G01X510400Y12790D02*
X509750D01*
G01X509840Y12880D02*
X510500D01*
G01X510600Y12990D02*
X509940D01*
G01X510040Y13080D02*
X510690D01*
G01X510790Y13190D02*
X510140D01*
G01X510230Y13290D02*
X510890D01*
G01X510980Y13380D02*
X510330D01*
G01X510430Y13490D02*
X511080D01*
G01X511180Y13580D02*
X510520D01*
G01X510620Y13690D02*
X511270D01*
G01X526440Y12690D02*
X525790D01*
G01X525980Y12490D02*
X526620D01*
G01X526390Y12100D02*
X526360Y12080D01*
G01X526680Y12390D02*
X526390Y12100D01*
G01X526690Y12410D02*
X526680Y12390D01*
G01Y12420D02*
X526690Y12410D01*
G01X526670Y12440D02*
X526680Y12420D01*
G01X526160Y12290D02*
X526580D01*
G01X509070Y31300D02*
X509100Y31320D01*
G01X509070Y30760D02*
Y31300D01*
G01X509080Y30740D02*
X509070Y30760D01*
G01X509130Y30630D02*
X509080Y30740D01*
G01X509140Y30620D02*
X509130Y30630D01*
G01X514320Y25030D02*
X509140Y30620D01*
G01X509070Y31290D02*
X509130D01*
G01X509070Y31190D02*
X509220D01*
G01X509310Y31080D02*
X509070D01*
G01Y30990D02*
X509410D01*
G01X509500Y30880D02*
X509070D01*
G01Y30790D02*
X509590D01*
G01X509690Y30690D02*
X509100D01*
G01X509170Y30580D02*
X509780D01*
G01X509870Y30490D02*
X509260D01*
G01X509350Y30380D02*
X509960D01*
G01X510060Y30290D02*
X509450D01*
G01X509540Y30190D02*
X510150D01*
G01X510240Y30080D02*
X509630D01*
G01X509720Y29990D02*
X510340D01*
G01X510430Y29880D02*
X509820D01*
G01X509910Y29790D02*
X510520D01*
G01X510620Y29690D02*
X510000D01*
G01X510100Y29580D02*
X510710D01*
G01X510800Y29490D02*
X510190D01*
G01X510280Y29380D02*
X510900D01*
G01X510990Y29290D02*
X510380D01*
G01X510470Y29190D02*
X511080D01*
G01X511180Y29080D02*
X510560D01*
G01X510650Y28990D02*
X511270D01*
G01X511360Y28880D02*
X510750D01*
G01X510840Y28790D02*
X511450D01*
G01X511550Y28690D02*
X510930D01*
G01X511030Y28580D02*
X511640D01*
G01X511730Y28490D02*
X511120D01*
G01X511210Y28380D02*
X511820D01*
G01X511920Y28290D02*
X511310D01*
G01X511400Y28190D02*
X512010D01*
G01X512100Y28080D02*
X511490D01*
G01X511580Y27990D02*
X512200D01*
G01X512290Y27880D02*
X511680D01*
G01X511770Y27790D02*
X512380D01*
G01X512480Y27690D02*
X511860D01*
G01X511950Y27580D02*
X512570D01*
G01X512660Y27490D02*
X512050D01*
G01X512140Y27380D02*
X512760D01*
G01X512850Y27290D02*
X512230D01*
G01X512320Y27190D02*
X512940D01*
G01X513040Y27080D02*
X512420D01*
G01X512510Y26990D02*
X513130D01*
G01X513220Y26880D02*
X512600D01*
G01X512690Y26790D02*
X513320D01*
G01X513410Y26690D02*
X512790D01*
G01X512880Y26580D02*
X513500D01*
G01X513590Y26490D02*
X512970D01*
G01X513070Y26380D02*
X513690D01*
G01X513780Y26290D02*
X513160D01*
G01X513250Y26190D02*
X513870D01*
G01X513970Y26080D02*
X513350D01*
G01X513530Y25880D02*
X514770D01*
G01X514780Y25690D02*
X513720D01*
G01X513470Y27980D02*
X513980D01*
G01X513430Y27940D02*
X513470Y27980D01*
G01X513430Y27480D02*
Y27940D01*
G01X513470Y27440D02*
X513430Y27480D01*
G01Y27880D02*
X523680D01*
G01X523610Y27690D02*
X513430D01*
G01Y27490D02*
X523450D01*
G01X516080Y28790D02*
X514650D01*
G01X514070Y28050D02*
X513980Y27980D01*
G01X514090Y28100D02*
X514070Y28050D01*
G01X514090Y28110D02*
Y28100D01*
G01X514210Y28360D02*
X514090Y28110D01*
G01X514230Y28370D02*
X514210Y28360D01*
G01X514660Y28790D02*
X514230Y28370D01*
G01X513990Y27990D02*
X514720D01*
G01X514830Y28320D02*
X514940Y28390D01*
G01X514660Y28150D02*
X514830Y28320D01*
G01X514640Y28040D02*
X514660Y28150D01*
G01X514730Y27980D02*
X514640Y28040D01*
G01X514800Y28290D02*
X514180D01*
G01X514130Y28190D02*
X514700D01*
G01X514650Y28080D02*
X514080D01*
G01X514340Y28490D02*
X516020D01*
G01Y28690D02*
X514550D01*
G01X514900Y25090D02*
X518130Y21610D01*
G01X514890Y25090D02*
X514900D01*
G01X514850Y25140D02*
X514890Y25090D01*
G01X514820Y25200D02*
X514850Y25140D01*
G01X514640Y27330D02*
X514820Y25200D01*
G01X514740Y27440D02*
X514640Y27330D01*
G01X515160Y21290D02*
X514690D01*
G01X514680Y21490D02*
X515140D01*
G01X515120Y21690D02*
X514660D01*
G01X514640Y21880D02*
X515110D01*
G01X515090Y22080D02*
X514620D01*
G01X514600Y22290D02*
X515070D01*
G01X515060Y22490D02*
X514590D01*
G01X514570Y22690D02*
X515040D01*
G01X515020Y22880D02*
X514550D01*
G01X514540Y23080D02*
X515010D01*
G01X514990Y23290D02*
X514520D01*
G01X514500Y23490D02*
X514970D01*
G01X514950Y23690D02*
X514490D01*
G01X514470Y23880D02*
X514940D01*
G01X514920Y24080D02*
X514450D01*
G01X514440Y24190D02*
X514950D01*
G01X515450Y24490D02*
X514420D01*
G01X514400Y24690D02*
X515270D01*
G01X514340Y25000D02*
X514320Y25030D01*
G01X514380Y24900D02*
X514340Y25000D01*
G01X514380Y24890D02*
Y24900D01*
G01Y24880D02*
Y24890D01*
G01X515080Y24880D02*
X514380D01*
G01X514280Y25080D02*
X514900D01*
G01X514830Y25190D02*
X514180D01*
G01X514090Y25290D02*
X514820D01*
G01X514810Y25380D02*
X514000D01*
G01X513900Y25490D02*
X514800D01*
G01X514790Y25580D02*
X513810D01*
G01X513620Y25790D02*
X514770D01*
G01X514760Y25990D02*
X514280D01*
G01X514070Y27440D02*
X513470D01*
G01X514170Y27350D02*
X514070Y27440D01*
G01X514290Y26000D02*
X514170Y27350D01*
G01X514130Y27380D02*
X514690D01*
G01X514640Y27290D02*
X514180D01*
G01X514190Y27190D02*
X514660D01*
G01Y27080D02*
X514190D01*
G01X514200Y26990D02*
X514670D01*
G01X514680Y26880D02*
X514210D01*
G01X514220Y26790D02*
X514690D01*
G01X514700Y26690D02*
X514230D01*
G01X514240Y26580D02*
X514710D01*
G01Y26490D02*
X514250D01*
G01Y26380D02*
X514720D01*
G01X514730Y26290D02*
X514270D01*
G01Y26190D02*
X514740D01*
G01X514750Y26080D02*
X514280D01*
G01X514120Y25930D02*
X509100Y31320D01*
G01X514230Y25900D02*
X514120Y25930D01*
G01X514290Y26000D02*
X514230Y25900D01*
G01X513440Y25990D02*
X514060D01*
G01X514380Y24880D02*
X514820Y19730D01*
G01X514830Y19690D02*
X515300D01*
G01X514800Y19990D02*
X515270D01*
G01X515250Y20190D02*
X514790D01*
G01X514770Y20380D02*
X515240D01*
G01X515220Y20580D02*
X514750D01*
G01X514730Y20790D02*
X515200D01*
G01X515190Y20990D02*
X514720D01*
G01X514710Y21080D02*
X515180D01*
G01X515170Y21190D02*
X514700D01*
G01X514680Y21380D02*
X515150D01*
G01X515140Y21580D02*
X514670D01*
G01X514650Y21790D02*
X515120D01*
G01X515100Y21990D02*
X514630D01*
G01X514620Y22190D02*
X515080D01*
G01X515060Y22380D02*
X514600D01*
G01X514580Y22580D02*
X515050D01*
G01X515030Y22790D02*
X514560D01*
G01X514550Y22990D02*
X515010D01*
G01X515000Y23190D02*
X514530D01*
G01X514510Y23380D02*
X514980D01*
G01X514960Y23580D02*
X514490D01*
G01X514480Y23790D02*
X514940D01*
G01X514930Y23990D02*
X514460D01*
G01X515090Y24210D02*
X517820Y21270D01*
G01X514970Y24230D02*
X515090Y24210D01*
G01X514920Y24130D02*
X514970Y24230D01*
G01X515190Y20880D02*
X514730D01*
G01X514740Y20690D02*
X515210D01*
G01X515230Y20490D02*
X514760D01*
G01X514780Y20290D02*
X515250D01*
G01X515260Y20080D02*
X514790D01*
G01X514810Y19880D02*
X515280D01*
G01X515290Y19790D02*
X514820D01*
G01X515110Y24190D02*
X515730D01*
G01X515920Y23990D02*
X515300D01*
G01X515480Y23790D02*
X516100D01*
G01X515360Y24580D02*
X514410D01*
G01X514390Y24790D02*
X515180D01*
G01X514990Y24990D02*
X514350D01*
G01X515050Y28400D02*
X514940Y28390D01*
G01X515100Y28310D02*
X515050Y28400D01*
G01X515100Y28080D02*
Y28310D01*
G01X515000Y27980D02*
X515100Y28080D01*
G01X514730Y27980D02*
X515000D01*
G01X514930Y28380D02*
X514240D01*
G01X515110Y29370D02*
X515140Y29390D01*
G01X515100Y29340D02*
X515110Y29370D01*
G01X515100Y29140D02*
Y29340D01*
G01X515090Y29100D02*
X515100Y29140D01*
G01X515070Y29050D02*
X515090Y29100D01*
G01X515020Y28990D02*
X515070Y29050D01*
G01X514930Y28950D02*
X515020Y28990D01*
G01X514660Y28790D02*
X514930Y28950D01*
G01X515140Y29380D02*
X515970D01*
G01X515100Y29190D02*
X517990D01*
G01X517980Y28990D02*
X515000D01*
G01X515050Y28380D02*
X516020D01*
G01Y28190D02*
X515100D01*
G01X515010Y27990D02*
X516120D01*
G01X517930Y20580D02*
X517290D01*
G01X517090Y20380D02*
X517740D01*
G01X517550Y20190D02*
X516900D01*
G01X516710Y19990D02*
X517350D01*
G01X517260Y19880D02*
X516610D01*
G01X516420Y19690D02*
X517060D01*
G01X517160Y19790D02*
X516510D01*
G01X517340Y21790D02*
X517970D01*
G01X517780Y21990D02*
X517160D01*
G01X516970Y22190D02*
X517590D01*
G01X517410Y22380D02*
X516780D01*
G01X516690Y22490D02*
X517310D01*
G01X517220Y22580D02*
X516600D01*
G01X516510Y22690D02*
X517130D01*
G01X517030Y22790D02*
X516410D01*
G01X516320Y22880D02*
X516940D01*
G01X516850Y22990D02*
X516230D01*
G01X516130Y23080D02*
X516760D01*
G01X516660Y23190D02*
X516040D01*
G01X515950Y23290D02*
X516570D01*
G01X516480Y23380D02*
X515850D01*
G01X515760Y23490D02*
X516380D01*
G01X516290Y23580D02*
X515670D01*
G01X515580Y23690D02*
X516200D01*
G01X516010Y23880D02*
X515390D01*
G01X515200Y24080D02*
X515820D01*
G01X515640Y24290D02*
X514440D01*
G01X514430Y24380D02*
X515550D01*
G01X517400Y23660D02*
X517440Y23620D01*
G01X516020Y28080D02*
X515100D01*
G01X516120Y27980D02*
X516020Y28080D01*
G01X515100Y28290D02*
X516020D01*
G01X517350Y28990D02*
X517460Y28880D01*
G01X517080Y28960D02*
X517350Y28990D01*
G01X516800Y28930D02*
X517080Y28960D01*
G01X516680Y28920D02*
X516800Y28930D01*
G01X516580Y28900D02*
X516680Y28920D01*
G01X516330Y28860D02*
X516580Y28900D01*
G01X516320Y28860D02*
X516330D01*
G01X516230Y28840D02*
X516320Y28860D01*
G01X516220Y28840D02*
X516230D01*
G01X516100Y28820D02*
X516220Y28840D01*
G01X516020Y28720D02*
X516100Y28820D01*
G01X516020Y28080D02*
Y28720D01*
G01X515960Y29390D02*
X515140D01*
G01X515980Y29380D02*
X515960Y29390D01*
G01X516010Y29370D02*
X515980Y29380D01*
G01X516040Y29350D02*
X516010Y29370D01*
G01X516120Y29330D02*
X516040Y29350D01*
G01X516140Y29340D02*
X516120Y29330D01*
G01X516380Y29380D02*
X516140Y29340D01*
G01X516880Y29450D02*
X516380Y29380D01*
G01X517000Y29460D02*
X516880Y29450D01*
G01X517060Y29460D02*
X517000D01*
G01X517220Y29480D02*
X517060Y29460D01*
G01X517360Y29490D02*
X517220Y29480D01*
G01X514820Y28880D02*
X516470D01*
G01X516020Y28580D02*
X514450D01*
G01X516120Y27980D02*
X521960D01*
G01X520030Y29490D02*
X517340D01*
G01X517360D02*
X517460Y29590D01*
G01X518580Y21120D02*
Y21260D01*
G01X518600Y21290D02*
X517810D01*
G01X517820Y21130D02*
X516660Y19940D01*
G01X517820Y21270D02*
Y21130D01*
G01X516810Y20080D02*
X517450D01*
G01X517640Y20290D02*
X517000D01*
G01X517190Y20490D02*
X517840D01*
G01X518030Y20690D02*
X517380D01*
G01X518120Y20790D02*
X518270D01*
G01X517480D02*
X518120D01*
G01X519290Y19690D02*
X519920D01*
G01X519820Y19790D02*
X519190D01*
G01X519100Y19880D02*
X519730D01*
G01X519640Y19990D02*
X519010D01*
G01X518920Y20080D02*
X519550D01*
G01X519450Y20190D02*
X518820D01*
G01X518730Y20290D02*
X519360D01*
G01X519270Y20380D02*
X518640D01*
G01X518550Y20490D02*
X519180D01*
G01X519080Y20580D02*
X518450D01*
G01X518360Y20690D02*
X518990D01*
G01X518900Y20790D02*
X518250D01*
G01X518620Y21080D02*
X517770D01*
G01X517820Y21190D02*
X518580D01*
G01X518700Y21380D02*
X517710D01*
G01X517620Y21490D02*
X518800D01*
G01X518900Y21580D02*
X517530D01*
G01X517440Y21690D02*
X518060D01*
G01X518270Y21610D02*
X519700Y23080D01*
G01X518130Y21610D02*
X518270D01*
G01X519600Y22990D02*
X520240D01*
G01X520050Y22790D02*
X519410D01*
G01X519320Y22690D02*
X519950D01*
G01X519860Y22580D02*
X519220D01*
G01X519120Y22490D02*
X519760D01*
G01X519670Y22380D02*
X519030D01*
G01X518930Y22290D02*
X519570D01*
G01X519470Y22190D02*
X518830D01*
G01X518740Y22080D02*
X519380D01*
G01X519280Y21990D02*
X518640D01*
G01X518550Y21880D02*
X519180D01*
G01X519090Y21790D02*
X518450D01*
G01X518350Y21690D02*
X518990D01*
G01X518710Y20990D02*
X517680D01*
G01X517580Y20880D02*
X518800D01*
G01X517870Y21880D02*
X517250D01*
G01X517060Y22080D02*
X517690D01*
G01X517500Y22290D02*
X516880D01*
G01X517490Y23620D02*
X519980D01*
G01X517440D02*
X517490D01*
G01X519990Y23380D02*
X520630D01*
G01X520440Y23190D02*
X519800D01*
G01X520920Y23690D02*
X517400D01*
G01X517440Y24650D02*
X517490D01*
G01X517400Y24610D02*
X517440Y24650D01*
G01X517400Y23660D02*
Y24610D01*
G01Y24490D02*
X520660D01*
G01X520690Y24290D02*
X517400D01*
G01Y24080D02*
X521310D01*
G01X521110Y23880D02*
X517400D01*
G01X517460Y28540D02*
Y28880D01*
G01X517500Y28490D02*
X517460Y28540D01*
G01X517450Y28880D02*
X520080D01*
G01X519950Y28490D02*
X517500D01*
G01X520000Y28540D02*
X519950Y28490D01*
G01X520000Y28820D02*
Y28540D01*
G01X517460Y28580D02*
X520000D01*
G01Y28690D02*
X517460D01*
G01Y28790D02*
X520000D01*
G01X519550Y29100D02*
Y29060D01*
G01X519450Y29200D02*
X519550Y29100D01*
G01X518010Y29200D02*
X519450D01*
G01X517910Y29100D02*
X518010Y29200D01*
G01X517910Y29060D02*
Y29100D01*
G01X518010Y28950D02*
X517910Y29060D01*
G01X519450Y28950D02*
X518010D01*
G01X519550Y29060D02*
X519450Y28950D01*
G01X519550Y29080D02*
X521520D01*
G01X521230Y29190D02*
X519460D01*
G01X517460Y29620D02*
Y29590D01*
G01X517500Y29660D02*
X517460Y29620D01*
G01X519950Y29660D02*
X517500D01*
G01X520000Y29620D02*
X519950Y29660D01*
G01X520000Y29520D02*
Y29620D01*
G01X517450Y29580D02*
X520000D01*
G01X517910Y29080D02*
X515080D01*
G01X515100Y29290D02*
X520860D01*
G01X520080Y29420D02*
X520000Y29520D01*
G01X520130Y29420D02*
X520080D01*
G01X520690Y29330D02*
X520130Y29420D01*
G01X520870Y29290D02*
X520690Y29330D01*
G01X520310Y29380D02*
X516440D01*
G01X520510Y28850D02*
X520920Y28760D01*
G01X520220Y28900D02*
X520510Y28850D01*
G01X520190Y28900D02*
X520220D01*
G01X520110Y28920D02*
X520190Y28900D01*
G01X520000Y28820D02*
X520110Y28920D01*
G01X520300Y28880D02*
X521890D01*
G01X520610Y24650D02*
X517490D01*
G01X517400Y24580D02*
X520660D01*
G01X520650Y24610D02*
X520610Y24650D01*
G01X520830Y24260D02*
X521030Y24460D01*
G01X520720Y24230D02*
X520830Y24260D01*
G01X520660Y24330D02*
X520720Y24230D01*
G01X520660Y24510D02*
Y24330D01*
G01Y24520D02*
Y24510D01*
G01X520650Y24610D02*
X520660Y24520D01*
G01X520860Y24290D02*
X521500D01*
G01X520660Y24380D02*
X517400D01*
G01X519510Y22880D02*
X520150D01*
G01X520070Y23560D02*
X519980Y23620D01*
G01X520050Y23450D02*
X520070Y23560D01*
G01X519700Y23080D02*
X520050Y23450D01*
G01X520340Y23080D02*
X519700D01*
G01X520030Y23580D02*
X520820D01*
G01X520730Y23490D02*
X520060D01*
G01X519900Y23290D02*
X520530D01*
G01X521050Y24490D02*
X521030Y24460D01*
G01X521690Y24490D02*
X521050D01*
G01D02*
X521860Y25330D01*
G01X521440Y24880D02*
X523700D01*
G01Y24690D02*
X521250D01*
G01X520950Y24380D02*
X521590D01*
G01X521400Y24190D02*
X517400D01*
G01Y23990D02*
X521210D01*
G01X521010Y23790D02*
X517400D01*
G01X521620Y20290D02*
X522080D01*
G01X522070Y20080D02*
X521600D01*
G01X521580Y19880D02*
X522050D01*
G01X522040Y19690D02*
X521570D01*
G01X521200Y28680D02*
X520920Y28760D01*
G01X521210Y28670D02*
X521200Y28680D01*
G01X521320Y28640D02*
X521210Y28670D01*
G01X521320Y28630D02*
Y28640D01*
G01X521430Y28590D02*
X521320Y28630D01*
G01X521440Y28580D02*
X521430Y28590D01*
G01X522300Y28580D02*
X521440D01*
G01X521160Y28690D02*
X522190D01*
G01X520990Y29250D02*
X520870Y29290D01*
G01X521100Y29230D02*
X520990Y29250D01*
G01X521340Y29150D02*
X521100Y29230D01*
G01X521450Y29110D02*
X521340Y29150D01*
G01X521510Y29090D02*
X521450Y29110D01*
G01X520800Y28790D02*
X522050D01*
G01X521730Y28990D02*
X519480D01*
G01X522050Y28030D02*
X521960Y27980D01*
G01X522040Y28130D02*
X522050Y28030D01*
G01X521970Y28240D02*
X522040Y28130D01*
G01X521950Y28260D02*
X521970Y28240D01*
G01X521650Y28480D02*
X521950Y28260D01*
G01X521640Y28490D02*
X521650Y28480D01*
G01X521630Y28490D02*
X521640D01*
G01X521440Y28580D02*
X521630Y28490D01*
G01X521970Y27990D02*
X523690D01*
G01X523670Y28190D02*
X522010D01*
G01X521780Y28380D02*
X523590D01*
G01X523700Y26380D02*
X521920D01*
G01X521890Y25360D02*
X521860Y25330D01*
G01X521920Y25420D02*
X521890Y25360D01*
G01X521920Y26440D02*
Y25420D01*
G01X521820Y25290D02*
X522490D01*
G01X522660Y25490D02*
X521920D01*
G01Y25690D02*
X522850D01*
G01X523040Y25880D02*
X521920D01*
G01Y25990D02*
X523700D01*
G01Y26190D02*
X521920D01*
G01X522030Y26520D02*
X522130Y26620D01*
G01X521960Y26520D02*
X522030D01*
G01X521920Y26480D02*
X521960Y26520D01*
G01X521920Y26440D02*
Y26480D01*
G01X521630Y25080D02*
X523700D01*
G01X522420Y24380D02*
X521950D01*
G01X521790Y24590D02*
X518580Y21260D01*
G01X521900Y24610D02*
X521790Y24590D01*
G01X521960Y24510D02*
X521900Y24610D01*
G01X521680Y21080D02*
X522150D01*
G01X522160Y21190D02*
X521690D01*
G01X521710Y21380D02*
X522180D01*
G01X522190Y21580D02*
X521730D01*
G01X521740Y21790D02*
X522210D01*
G01X522220Y21990D02*
X521760D01*
G01X521770Y22190D02*
X522240D01*
G01X522260Y22380D02*
X521790D01*
G01X521810Y22580D02*
X522270D01*
G01X522290Y22790D02*
X521820D01*
G01X521840Y22990D02*
X522310D01*
G01X522320Y23190D02*
X521860D01*
G01X521870Y23380D02*
X522340D01*
G01X522350Y23580D02*
X521890D01*
G01X521900Y23790D02*
X522370D01*
G01X522390Y23990D02*
X521920D01*
G01X521940Y24190D02*
X522400D01*
G01X521790Y24580D02*
X521150D01*
G01X521670Y20880D02*
X522140D01*
G01X522120Y20690D02*
X521650D01*
G01X521640Y20490D02*
X522100D01*
G01X522090Y20380D02*
X521630D01*
G01X521610Y20190D02*
X522080D01*
G01X522060Y19990D02*
X521590D01*
G01X521580Y19790D02*
X522050D01*
G01X521660Y29030D02*
X521510Y29090D01*
G01X521670Y29020D02*
X521660Y29030D01*
G01X522920Y28740D02*
X522980Y28750D01*
G01X522910Y28740D02*
X522920D01*
G01X522800Y28710D02*
X522910Y28740D01*
G01X522790Y28710D02*
X522800D01*
G01X522660Y28660D02*
X522790Y28710D01*
G01X522660Y28650D02*
Y28660D01*
G01X522600Y28620D02*
X522660Y28650D01*
G01X522580Y28600D02*
X522600Y28620D01*
G01X522520Y28550D02*
X522580Y28600D01*
G01X522500Y28530D02*
X522520Y28550D01*
G01X522360Y28530D02*
X522500D01*
G01X522180Y28700D02*
X522360Y28530D01*
G01X522170Y28710D02*
X522180Y28700D01*
G01X521670Y29020D02*
X522170Y28710D01*
G01X522730Y28690D02*
X523250D01*
G01X523300Y27380D02*
X522140D01*
G01X522190Y27330D02*
X522130Y26620D01*
G01X522100Y26580D02*
X522650D01*
G01X522940Y27310D02*
X522970Y27300D01*
G01X522860Y27320D02*
X522940Y27310D01*
G01X522790Y27340D02*
X522860Y27320D01*
G01X522780Y27340D02*
X522790D01*
G01X522650Y27250D02*
X522780Y27340D01*
G01X522600Y26640D02*
X522650Y27250D01*
G01X522700Y26530D02*
X522600Y26640D01*
G01X522700Y27290D02*
X522190D01*
G01X522090Y27440D02*
X514740D01*
G01X522190Y27330D02*
X522090Y27440D01*
G01X521730Y25190D02*
X522550D01*
G01X522520Y25340D02*
X523070Y25920D01*
G01X522490Y25290D02*
X522520Y25340D01*
G01X522490Y25250D02*
Y25290D01*
G01X522590Y25140D02*
X522490Y25250D01*
G01X522950Y25790D02*
X521920D01*
G01Y25580D02*
X522750D01*
G01X522560Y25380D02*
X521900D01*
G01X521920Y24580D02*
X522450D01*
G01X521640Y20580D02*
X522110D01*
G01X522130Y20790D02*
X521660D01*
G01X521680Y20990D02*
X522140D01*
G01X522170Y21290D02*
X521700D01*
G01X521710Y21490D02*
X522180D01*
G01X522200Y21690D02*
X521730D01*
G01X521750Y21880D02*
X522210D01*
G01X522230Y22080D02*
X521770D01*
G01X521780Y22290D02*
X522250D01*
G01X522270Y22490D02*
X521800D01*
G01X521810Y22690D02*
X522280D01*
G01X522300Y22880D02*
X521830D01*
G01X521850Y23080D02*
X522310D01*
G01X522330Y23290D02*
X521860D01*
G01X521880Y23490D02*
X522340D01*
G01X522360Y23690D02*
X521900D01*
G01X521910Y23880D02*
X522380D01*
G01X522400Y24080D02*
X521930D01*
G01X521940Y24290D02*
X522410D01*
G01X522430Y24490D02*
X521960D01*
G01X522440Y24570D02*
X522530Y24660D01*
G01X522860Y26520D02*
X522980D01*
G01X522700Y26530D02*
X522860Y26520D01*
G01X522610Y26690D02*
X522140D01*
G01X522150Y26790D02*
X522620D01*
G01Y26880D02*
X522160D01*
G01Y26990D02*
X522630D01*
G01X522640Y27080D02*
X522170D01*
G01X522180Y27190D02*
X522650D01*
G01X523050Y28750D02*
X522980D01*
G01X523060Y28740D02*
X523050Y28750D01*
G01X523320Y28670D02*
X523060Y28740D01*
G01X523330Y28660D02*
X523320Y28670D01*
G01X523530Y28490D02*
X523330Y28660D01*
G01X523540Y28480D02*
X523530Y28490D01*
G01X523660Y28250D02*
X523540Y28480D01*
G01X523670Y28230D02*
X523660Y28250D01*
G01X523690Y27950D02*
X523670Y28230D01*
G01X523690Y27940D02*
Y27950D01*
G01X523610Y27680D02*
X523690Y27940D01*
G01X523600Y27670D02*
X523610Y27680D01*
G01X523440Y27470D02*
X523600Y27670D01*
G01X523430Y27450D02*
X523440Y27470D01*
G01X523200Y27330D02*
X523430Y27450D01*
G01X523180Y27330D02*
X523200D01*
G01X523060Y27310D02*
X523180Y27330D01*
G01X523050Y27310D02*
X523060D01*
G01X522990Y27300D02*
X523050Y27310D01*
G01X522970Y27300D02*
X522990D01*
G01X522560Y28580D02*
X523420D01*
G01X523530Y28490D02*
X521640D01*
G01X521920Y28290D02*
X523640D01*
G01X523680Y28080D02*
X522050D01*
G01X523540Y27580D02*
X513430D01*
G01Y27790D02*
X523640D01*
G01X523950Y27490D02*
X524580D01*
G01X524680Y27580D02*
X524050D01*
G01X524140Y27690D02*
X524780D01*
G01X524870Y27790D02*
X524240D01*
G01X524340Y27880D02*
X524970D01*
G01X525060Y27990D02*
X524440D01*
G01X524530Y28080D02*
X525160D01*
G01X525260Y28190D02*
X524630D01*
G01X524730Y28290D02*
X525360D01*
G01X525550Y28490D02*
X524920D01*
G01X525110Y28690D02*
X525740D01*
G01X524490Y27380D02*
X523860D01*
G01X523760Y27290D02*
X524390D01*
G01X524290Y27190D02*
X523660D01*
G01X523560Y27080D02*
X524200D01*
G01X524100Y26990D02*
X523470D01*
G01X523370Y26880D02*
X524010D01*
G01X523910Y26790D02*
X523280D01*
G01X523180Y26690D02*
X523810D01*
G01X523660Y24660D02*
X522530D01*
G01X523700Y24680D02*
X523660Y24660D01*
G01X523700Y24690D02*
Y24680D01*
G01Y26510D02*
Y24690D01*
G01Y26520D02*
Y26510D01*
G01X523730Y26600D02*
X523700Y26520D01*
G01X523180Y25940D02*
X523070Y25920D01*
G01X523240Y25840D02*
X523180Y25940D01*
G01X523240Y25240D02*
Y25840D01*
G01X523140Y25140D02*
X523240Y25240D01*
G01X522590Y25140D02*
X523140D01*
G01X523210Y25880D02*
X523700D01*
G01Y25790D02*
X523240D01*
G01Y25690D02*
X523700D01*
G01Y25580D02*
X523240D01*
G01Y25490D02*
X523700D01*
G01Y25380D02*
X523240D01*
G01Y25290D02*
X523700D01*
G01Y25190D02*
X523190D01*
G01X523700Y24990D02*
X521530D01*
G01X521340Y24790D02*
X523700D01*
G01Y26080D02*
X521920D01*
G01Y26290D02*
X523700D01*
G01Y26490D02*
X521920D01*
G01X522980Y26520D02*
X523050Y26550D01*
G01X523080Y26580D02*
X523720D01*
G01X523050Y26550D02*
X527630Y31290D01*
G01X527660Y30680D02*
X523730Y26600D01*
G01X524820Y28380D02*
X525450D01*
G01X525640Y28580D02*
X525010D01*
G01X525210Y28790D02*
X525840D01*
G01X525940Y28880D02*
X525310D01*
G01X525400Y28990D02*
X526030D01*
G01X526130Y29080D02*
X525500D01*
G01X525600Y29190D02*
X526220D01*
G01X526320Y29290D02*
X525690D01*
G01X525880Y29490D02*
X526510D01*
G01X526710Y29690D02*
X526080D01*
G01X526270Y29880D02*
X526900D01*
G01X526800Y29790D02*
X526180D01*
G01X526370Y29990D02*
X526990D01*
G01X527090Y30080D02*
X526460D01*
G01X526560Y30190D02*
X527190D01*
G01X527290Y30290D02*
X526660D01*
G01X526750Y30380D02*
X527380D01*
G01X527480Y30490D02*
X526850D01*
G01X526950Y30580D02*
X527570D01*
G01X527680Y30790D02*
X527140D01*
G01X527670Y30710D02*
X527680Y30790D01*
G01X527660Y30680D02*
X527670Y30710D01*
G01X527050Y30690D02*
X527660D01*
G01X527680Y31280D02*
X527630Y31290D01*
G01X527680Y30790D02*
Y31280D01*
G01X527620Y31290D02*
X527660D01*
G01X527680Y31190D02*
X527530D01*
G01X527430Y31080D02*
X527680D01*
G01Y30990D02*
X527330D01*
G01X527240Y30880D02*
X527680D01*
G01X526610Y29580D02*
X525980D01*
G01X525790Y29380D02*
X526420D01*
G54D19*
G01X535218Y91504D02*
G02X535122Y91272I-328J0D01*
G02X534934Y91194I-188J188D01*
G01X534556D01*
G02X534382Y91266I0J246D01*
G02X534298Y91469I203J203D01*
G01Y95301D01*
X533415D01*
X533391Y95277D01*
G01X535292Y95191D02*
X535203Y95102D01*
X535212Y91475D01*
M02*
